5
5
4
4
3
3
2
2
1
1
D D
C C
B B
A A
Lightning - PMC PEB
PCB P/N: 15105Version: 1Project Code:BPD00Q010001
Title
Size Document Number Rev
Date: Sheet o f
Lightning PMC PEB -11COVER PAGEA41 60Friday, March 31, 2017Lightning PMC PEB -1http://www.wiwynn.com8F, 90, Sec.1, Xintai 5th Rd., Xizhi Dist.,New Taipei City 22102, Taiwan (R.O.C.)
Title
Size Document Number Rev
Date: Sheet o f
Lightning PMC PEB -11COVER PAGEA41 60Friday, March 31, 2017Lightning PMC PEB -1http://www.wiwynn.com8F, 90, Sec.1, Xintai 5th Rd., Xizhi Dist.,New Taipei City 22102, Taiwan (R.O.C.)
Title
Size Document Number Rev
Date: Sheet o f
Lightning PMC PEB -11COVER PAGEA41 60Friday, March 31, 2017Lightning PMC PEB -1http://www.wiwynn.com8F, 90, Sec.1, Xintai 5th Rd., Xizhi Dist.,New Taipei City 22102, Taiwan (R.O.C.)



5
5
4
4
3
3
2
2
1
1
D D
C C
B B
A A
TABLE OF CONTENTS
CLOCK TREE
12
15
16
17
20
21
13
14
18
19
03
04
05
08
11
10
02
07
06
09
01
PAGE TITLE PAGEPAGE PAGE TITLE
I2C _BUFFER
I2C\SMBUS DIAGRAM
SPI MUX
AST2400 I2C DEVICE
AST2400 I2C DDR LPC
AST2400 UART LAN SPI
SYSTEM BLOCK DIAGRAM
AST2400 FAN ADC VGA JTAG
AST2400 Power
AST2400 Strapping
COVER PAGE
POWER DISTRIBUTION DIAGRAM
POWER FLOW & SEQUENCE
RESET DIAGRAM
TABLE OF CONTENTS
AST2400_VOLTAGE SENSE
BLANK
LAN CONNECTOR
USB2.0 x1
STACK-UP INFORMATION
33
36
37
38
34
35
39
40
24
25
26
29
32
22
23
27
28
30
31
miniSAS HD A SFF8644
BLANK
Heart Beat
CLOCK GENERATOR
RESET
PM8536 PCIE STACKS 0-1
PM8536 PCIE STACKS 2-3
LED
DEBUG PORT
TPM CONN
PM8536 PCIE STACKS 4-5
PM8536 CLOCK & RESET
PM8536 I2C & LBI
RTC
200 PIN G/F
PM8536 VDD VDDO AVD_PCIE
PM8536 AVD_PCIE
PM8536 VSS
miniSAS HD B SFF8644
PWRSW_P5V_STBY_SY8120
52
53
54
43
44
45
48
51
41
42
46
47
49
50
PWRLDO_P1V8_PWR_TPS74801
MBP CONN
PWRLDO_P1V53_PWR_TPS74801
PWRLDO_P1V26_PWR_TPS74801
PWRSW_P0V9_TPS53355A
PWRSW_P0V9_E_TPS53355A
GPIO EXPANDER
INTEL I210
INTEL I210 DECOUPLING
ME
SPI NOR FLASH & EEPROM
12V-DCIN_ADM1278 HSC
PWRSW_P3V3_PWR_TPS53319
55 History EVT1
History EVT256
57 History DVT
NOPOP=no populated
562R2F-GP562 = 562 ohm, (2K2R means 2.2K ohm)2 = size 0402F = 1% toleranceGP= Green Part (RoHS)Wiwynn RC size code as below:1 = 02012= 04023= 06035= 08056= 1206Wiwynn R tolerance code as below:D=0.5%F= 1%J= 5%
SCD1U10V2KX-5GPD1U = 0.1uF (2D2U means 2.2uF)10Voltage (6D3V means 6.3V)2 = size 0402, K toleranceK=tolerance[Wiwynn C code as below:]G=2%J=5%K=10%M=20%X=temp characteristics[(RoHS) Wiwynn C Series/Temp]N=NPOX=X7R/X5RY=Y5V-5=different symbol/customerGP= Green Part (RoHS)
58 History DVT
59 History DVT
60 History PVT
Title
Size Document Number R e v
Date: Sheet o f
Lightning PMC PEB -11TABLE OF CONTENTSA32 60Friday, March 31, 2017Lightning PMC PEB -1http://www.wiwynn.com8F, 90, Sec.1, Xintai 5th Rd., Xizhi Dist.,New Taipei City 22102, Taiwan (R.O.C.)
Title
Size Document Number R e v
Date: Sheet o f
Lightning PMC PEB -11TABLE OF CONTENTSA32 60Friday, March 31, 2017Lightning PMC PEB -1http://www.wiwynn.com8F, 90, Sec.1, Xintai 5th Rd., Xizhi Dist.,New Taipei City 22102, Taiwan (R.O.C.)
Title
Size Document Number R e v
Date: Sheet o f
Lightning PMC PEB -11TABLE OF CONTENTSA32 60Friday, March 31, 2017Lightning PMC PEB -1http://www.wiwynn.com8F, 90, Sec.1, Xintai 5th Rd., Xizhi Dist.,New Taipei City 22102, Taiwan (R.O.C.)



5
5
4
4
3
3
2
2
1
1
D D
C C
B B
A A
PMCPM8536
BMCAST2400
PCIE STACK1
G/F
PCIE STACK5
Ext. Mini SAS HD 4X4SFF8644
Ext. Mini SAS HD 4X4SFF8644
PCIE STACK2
PCIE STACK3
PCIE STACK4
PCIE STACK0
I2C Bus
UART Bus 4 Pin Header
UART Bus
SWITCH
Debug Connector
4 Pin Header
I2C BusI2C [1]
I2C [0]
GPIO EXPANDERMAX7311
I2C [14]
I2C [13]
I2C [12]
I2C [11]
RMII
IntelI210-AT
RJ45Connector
USBUSBConnector
I2C [10]
I2C [3]
I2C [2]
I2C [1]
I2C [4]
I2C Bus
I2C Bus
I2C Bus
I2C Bus
MINI SAS HD 4X4SFF 8644
I2C Bus
I2C Bus
I2C Bus
I2C Bus
I2C [8]
I2C [9]
I2C Bus
I2C Bus
MINI SAS HD 4X4SFF 8644
I2C BUFFERPCA9511
I2C BUFFERPCA9511
I2C BUFFERPCA9511I2C BusI2C [7]
CLOCKBUFFER9ZXL1231
CLOCKBUFFER9ZXL1231
TEMP SENSORTMP75 VOLTAGE SENSORADS1015
TEMP SENSORTMP75
TEMP SENSORTMP75
TEMP SENSORTMP75
SSDSMBus SWPCA9547
SSDSMBus SWPCA9547
EEPROM24LC64T
I2C BUFFERPCA9511I2C BusI2C [6]
EEPROM24LC64T
LED DRIVERPCA9550 POWER MONITOR FANCONTROLLER
I2C [5]
I2C Bus
EEPROM24LC64T RTCPCF8563 12V HSADM1278
TEMP SENSORTMP421 TEMP SENSORTMP75 TEMP SENSORTMP75
FCB
CLOCKBUFFER9ZXL1231
CLOCKBUFFER9ZXL1231
PDPB
TPM CONNSLB96459FGV0431AKLFT-GP
Clock Gen. TEMP SENSORMAX6654MEE
DSP
USP
USP
MBPConnector
MBP
SPI MUX
SPI Flash
SPI
Title
Size Document Number R e v
Date: Sheet o f
Lightning PMC PEB -11SYSTEM BLOCK DIAGRAMCustom3 60Friday, March 31, 2017Lightning PMC PEB -1http://www.wiwynn.com8F, 90, Sec.1, Xintai 5th Rd., Xizhi Dist.,New Taipei City 22102, Taiwan (R.O.C.)
Title
Size Document Number R e v
Date: Sheet o f
Lightning PMC PEB -11SYSTEM BLOCK DIAGRAMCustom3 60Friday, March 31, 2017Lightning PMC PEB -1http://www.wiwynn.com8F, 90, Sec.1, Xintai 5th Rd., Xizhi Dist.,New Taipei City 22102, Taiwan (R.O.C.)
Title
Size Document Number R e v
Date: Sheet o f
Lightning PMC PEB -11SYSTEM BLOCK DIAGRAMCustom3 60Friday, March 31, 2017Lightning PMC PEB -1http://www.wiwynn.com8F, 90, Sec.1, Xintai 5th Rd., Xizhi Dist.,New Taipei City 22102, Taiwan (R.O.C.)



5
5
4
4
3
3
2
2
1
1
D D
C C
B B
A A
Change list :- P3V3_STBY:* Remove MCP2210T-I-MQ-GP (U202) -- 0.095 A* Remove BCM5221A4KMLG-GP (U20) -- 0.11 A* Remove OSC-125MHZ-3-GP (X10) -- 0.06 A* Remove ADS1015IDGSR-GP (U14,U17) -- 0.2 A* Remove USB2514B-AEZC-TR-GP (U3) -- 0.065 A
* Add SLB9645TT1-2FW133-32-GP (TPM though CN11) -- 0.025 A* Add WGI210AT-2-GP (U20) -- 0.242 A* Add W25Q256FVFIQ-GP (U36) -- 0.025 A* Add W25Q80DVSSIG-1-GP (U44) -- 0.025 A* Add TCA9554APWR-GP (U54,U55,U56) -- 0.48 A* Add SN74AUP1T97DCKR-GP (U45 U49) -- 0.1 A* Add SN74LVC1G07DCKRG4-2-GP (U42 U52 U53) -- 0.3 A
- P1V8_STBY* Remove N25Q128A13BSF40F-GP (U26) -- 0.02 A
Title
Size Document Number R e v
Date: Sheet o f
Lightning PMC PEB -11POWER DISTRIBUTION DIAGRAMA34 60Friday, March 31, 2017Lightning PMC PEB -1http://www.wiwynn.com8F, 90, Sec.1, Xintai 5th Rd., Xizhi Dist.,New Taipei City 22102, Taiwan (R.O.C.)
Title
Size Document Number R e v
Date: Sheet o f
Lightning PMC PEB -11POWER DISTRIBUTION DIAGRAMA34 60Friday, March 31, 2017Lightning PMC PEB -1http://www.wiwynn.com8F, 90, Sec.1, Xintai 5th Rd., Xizhi Dist.,New Taipei City 22102, Taiwan (R.O.C.)
Title
Size Document Number R e v
Date: Sheet o f
Lightning PMC PEB -11POWER DISTRIBUTION DIAGRAMA34 60Friday, March 31, 2017Lightning PMC PEB -1http://www.wiwynn.com8F, 90, Sec.1, Xintai 5th Rd., Xizhi Dist.,New Taipei City 22102, Taiwan (R.O.C.)



5
5
4
4
3
3
2
2
1
1
D D
C C
B B
A A
P1V26_PWR
TPS74801
3.3V/0.766A AST2400  0.766A1.26V/0.766A
3.3V/5.813A
P0V9
TPS53355
0.92V/16.7A12V/1.600A/80% PM8536AVD_PCIE        12.03AAVD_PCIE_Q    0.25AAVD_PCIE_TX   4.42A
P1V8_PWR
TPS74801
3.3V/0.055A
PM8536 VDDO 0.0147ASPI FLASH           0.02Aothers                  0.0203A1.8V/0.055A
P1V53_PWR
TPS74801
3.3V/0.662A AST2400  0.452ADDR3        0.210A
1.53V/0.662A
P12V_PCIE
OCP=>7.297x1.48=10.8 A
12V/7.297AP12V
P3V3_PWR
 TPS53319
3.3V/7.296A12V/2.229A/90% AST2400             0.191ASN74LVC1G08   1.7ASN74LVC1G07   0.7AMAX7311           1ALEDs                     0.8A3V3 PULL UP     0.232Aothers                 1.19A
ADM1278   0.240ATPS53355    0.162ATPS53318    0.081A
P5V_STBY
SY8120
12V/0.483A
5V/1.001A TPS2065             0.001AUSB2.0 conn     0.9ALEDs                     0.1A
12V/0.463A/90%
P0V9_E
TPS53355
0.92V/26.32A12V/2.522A/80%
12V/7.31A
PM8536 DUT_VDD  26.32A
P5V_STBY
P3V3_PWR
P12V
P1V8_PWR
P1V53_PWR
P1V26_PWR
P0V9
P0V9_E
P1V26_PWR
FM_BMC_RESET_N
BMC_PERST#_R
AST2400  
System Power sequence
1ms
100ms
PM8536 (Dev2 FW)
HOST1_RST_N_LS
PM8536_RST# 
100ms
100us
P0V9
Title
Size Document Number R ev
Date: Sheet o f
Lightning PMC PEB -11POWER FLOWCustom5 60Friday, March 31, 2017Lightning PMC PEB -1http://www.wiwynn.com8F, 90, Sec.1, Xintai 5th Rd., Xizhi Dist.,New Taipei City 22102, Taiwan (R.O.C.)
Title
Size Document Number R ev
Date: Sheet o f
Lightning PMC PEB -11POWER FLOWCustom5 60Friday, March 31, 2017Lightning PMC PEB -1http://www.wiwynn.com8F, 90, Sec.1, Xintai 5th Rd., Xizhi Dist.,New Taipei City 22102, Taiwan (R.O.C.)
Title
Size Document Number R ev
Date: Sheet o f
Lightning PMC PEB -11POWER FLOWCustom5 60Friday, March 31, 2017Lightning PMC PEB -1http://www.wiwynn.com8F, 90, Sec.1, Xintai 5th Rd., Xizhi Dist.,New Taipei City 22102, Taiwan (R.O.C.)



5
5
4
4
3
3
2
2
1
1
D D
C C
B B
A A
BMCAST2400
Mini SASportA
SecureSPIFlash
SPI
BMCSPIFlash
Buttom
SW
I/O Expander x4
I2C
PERST
BMC_RST
HOST
USB1.1
PERST_SSD#
RESET
PEB
PERST
SPI
BMC_PERST#
INTELI210
MBP
USB CONN
DDR3
GPIO_RST
OCP
DP_RST
GPIO_RST
GPIO_RST
BMC_RST
PMC Reset Diagram
SSD*15
PDPB
NOPOP
NOPOP
Slide
 Header S
D
GHB_OUT
ADM6315
P3V3
N-MOS*2 ADM6315
P3V3
LevelShiftNOPOP
I2C
CN15A -> USB2.0
TCA9554
TPM
RST_BMC_EXTRST_N
Logic
Logic
GPIOG5 NOPOP
CN16A -> USB1.1
Title
Size Document Number R e v
Date: Sheet o f
Lightning PMC PEB -11RESET DIAGRAMA36 60Friday, March 31, 2017Lightning PMC PEB -1http://www.wiwynn.com8F, 90, Sec.1, Xintai 5th Rd., Xizhi Dist.,New Taipei City 22102, Taiwan (R.O.C.)
Title
Size Document Number R e v
Date: Sheet o f
Lightning PMC PEB -11RESET DIAGRAMA36 60Friday, March 31, 2017Lightning PMC PEB -1http://www.wiwynn.com8F, 90, Sec.1, Xintai 5th Rd., Xizhi Dist.,New Taipei City 22102, Taiwan (R.O.C.)
Title
Size Document Number R e v
Date: Sheet o f
Lightning PMC PEB -11RESET DIAGRAMA36 60Friday, March 31, 2017Lightning PMC PEB -1http://www.wiwynn.com8F, 90, Sec.1, Xintai 5th Rd., Xizhi Dist.,New Taipei City 22102, Taiwan (R.O.C.)



5
5
4
4
3
3
2
2
1
1
D D
C C
B B
A A
Title
Size Document Number Rev
Date: Sheet o f
Lightning PMC PEB -11CLOCK TREECustom7 60Friday, March 31, 2017Lightning PMC PEB -1http://www.wiwynn.com8F, 90, Sec.1, Xintai 5th Rd., Xizhi Dist.,New Taipei City 22102, Taiwan (R.O.C.)
Title
Size Document Number Rev
Date: Sheet o f
Lightning PMC PEB -11CLOCK TREECustom7 60Friday, March 31, 2017Lightning PMC PEB -1http://www.wiwynn.com8F, 90, Sec.1, Xintai 5th Rd., Xizhi Dist.,New Taipei City 22102, Taiwan (R.O.C.)
Title
Size Document Number Rev
Date: Sheet o f
Lightning PMC PEB -11CLOCK TREECustom7 60Friday, March 31, 2017Lightning PMC PEB -1http://www.wiwynn.com8F, 90, Sec.1, Xintai 5th Rd., Xizhi Dist.,New Taipei City 22102, Taiwan (R.O.C.)



5
5
4
4
3
3
2
2
1
1
D D
C C
B B
A A
STACK-UP INFORMATION
Title
Size Document Number R e v
Date: Sheet o f
Lightning PMC PEB -11STACK-UP IMFORMATIONA38 60Friday, March 31, 2017Lightning PMC PEB -1http://www.wiwynn.com8F, 90, Sec.1, Xintai 5th Rd., Xizhi Dist.,New Taipei City 22102, Taiwan (R.O.C.)
Title
Size Document Number R e v
Date: Sheet o f
Lightning PMC PEB -11STACK-UP IMFORMATIONA38 60Friday, March 31, 2017Lightning PMC PEB -1http://www.wiwynn.com8F, 90, Sec.1, Xintai 5th Rd., Xizhi Dist.,New Taipei City 22102, Taiwan (R.O.C.)
Title
Size Document Number R e v
Date: Sheet o f
Lightning PMC PEB -11STACK-UP IMFORMATIONA38 60Friday, March 31, 2017Lightning PMC PEB -1http://www.wiwynn.com8F, 90, Sec.1, Xintai 5th Rd., Xizhi Dist.,New Taipei City 22102, Taiwan (R.O.C.)



5
5
4
4
3
3
2
2
1
1
D D
C C
B B
A A
BUFFER
U201
U199
U198
U200
EU1
EU2
4.7KΩ
P3V3_STBY
4.7KΩ
P3V3_STBY
4.7KΩ
P3V3_STBY
4.7KΩ
P3V3_STBY
P3V3_STBY P3V3_STBY
CLK Gen--U1969FGV0431ADDR: 0xD0
TEMP SENSOR --U4MAX6654ADDR: 0x30
HOT SWAP IC--U2ADM1278ADDR: 0x11
TEMP SENSOR 2--U134TMP75ADDR: 0x94
TEMP SENSOR 3--U136TMP75ADDR: 0x9A
TEMP SENSOR 1--U15TMP421ADDR: 0x98
SWITCH_1--EU17PCA9547ADDR: 0xE4
SWITCH_1--EU16PCA9547ADDR: 0xE2
PMC-PEB PDPB FCB
RETIMER
RETIMER
SEVER 4.7KΩ
P3V3_STBY
PMC  PM8536
BMC AST2400
EEPROM--U1624LC64ADDR: 0xA0
RTC--U43PCF8563TADDR: 0xA2
CLOCK BUFFER9ZXL1231ADDR: 0xD8
CLOCK BUFFER9ZXL1231ADDR: 0xCA
P3V3_STBY
4.7KΩ
4.7KΩ 4.7KΩ
I2C_1(M)
GPIO EXPANDERMAX7311  4PFADDR: 0x40I2C_0(S)
BUFFER
BUFFER
4.7KΩ EEPROM--U524LC64ADDR:0xA2Cload=10pF
CURRENT SHUNT--PU1HOT-SWAPADM1276ADDR: 0x44
FAN Controler-U1NCT7904DADDR: 0x5ACload=12pF
LED DRIVER--U6PCA9550ADDR:0xC0
I2C_13(S)
GPIO EXPANDERMAX7311  4PFADDR: 0x4E
GPIO EXPANDERMAX7311  4PFADDR: 0x4C
4.7KΩ
P3V3_STBY
I2C_14(S)
I2C_8(M)
I2C_5(M)
I2C_6(M)
I2C_7(M)
I2C_1(S)
I2C_10(M)
I2C_2(S)
I2C_4(S)
I2C_3(S)
I2C_11(S)
I2C_12(S)
4.7KΩ
P3V3_STBY
4.7KΩ
P3V3_STBY
4.7KΩ
P3V3_STBY
4.7KΩ
P3V3_STBY
4.7KΩ
P3V3_STBY
EEPROM--U5024LC64ADDR:0xA2
VOLTAGE SENSOR--u53ADS1015ADDR: 0x90
TEMP SENSOR 1--U47TMP75ADDR: 0x92
DUALMOS
DUALMOS
I2C SWITCH--U11
Address 0xEA
LEOPARD
USB HUB--U14 RETIMER--U2CLOCK BUFF--U5USB2514B-AEZC89HT0832PZCHLG8-GP9DBV0631BKLF-GP
EEPROM--U24
TEMP SENSOR 2--U48TMP75ADDR: 0x94
TEMP SENSOR 3--U49TMP75ADDR: 0x96
TEMP SENSOR 4--U51TMP75ADDR: 0x98
I2C_a
CLOCK BUFFER--EU49ZXL1231ADDR: 0xCE
CLOCK BUFFER--EU39ZXL1231ADDR: 0xDE
Address 0xD6 Address 0x58 Master Address 0xA0
Slave Address 0xC0
Address 0xA0
PCA9544APW-GP
GPIO EXPANDERMAX7311  4PFADDR: 0x42
U203
GPIO EXPANDERMAX7311 4PFADDR: 0x4E
I2C_2(M) I2C_3(M)
EEPROM     8PFCAT24C128WI-GT3ADDR: 0xA0U10
4.7KΩ
P3V3_STBY
4.7KΩ
P3V3_STBY
P3V3_STBY
M.2
M.2
SSD SMBUSSSD:0,1,2,5,6,7,10,11
M.2
TMP SENSORTMP75
SSD SMBUSSSD:3,4,8,9,12,13,14
Address: 0xE6
SWITCH
U4
Address: 0xE6
SWITCH
TPM module
ADDR: 0x40
I2C_B
I2C_D
I2C_AMBP Conn.
BUFFERI2C_9(M)
GPIO EXPANDER--U56TCA9554ADDR: 0x40GPIOQ7 Alert
GPIO EXPANDER--U54TCA9554ADDR: 0x40 SRST#
GPIO EXPANDER--U55TCA9554ADDR: 0x40
I/O EXP--U19
PCA9536DGKR-GP
Address 0x82
LAN--U20I210 5PF
Note:(M):Master(S):Slave
ADDR: 0x30oBMC: 0x20
RISER
I2C SWITCH--U10PCA9540BDPAddress 0XE0
U4
U1 Address: 0x98
ADDR: 0xA0
Address: 0x98U1
TMP SENSORTMP75
Cload=10pF
Cload=5pF Cload=6pF
Cload=3pF
Cload=3pF
Cload=3pF
Cload=5pF Cload=7pF Cload=5pF Cload=3pF Cload=5pF Cload=10pF
Cload=10pF
Cload=3pF
Cload=3pF
Cload=3pF
Cload=3pF
Cload=10pF
Cload=19pF
Cload=5pF
Cload=5pF
Cload=19pF
Cload=5pF
Cload=5pF
Cload=3.7pF
Cload=5pF
Title
Size Document Number R e v
Date: Sheet o f
Lightning PMC PEB -11I2C/SMBUS DIAGRAMCustom9 60Friday, March 31, 2017Lightning PMC PEB -1http://www.wiwynn.com8F, 90, Sec.1, Xintai 5th Rd., Xizhi Dist.,New Taipei City 22102, Taiwan (R.O.C.)
Title
Size Document Number R e v
Date: Sheet o f
Lightning PMC PEB -11I2C/SMBUS DIAGRAMCustom9 60Friday, March 31, 2017Lightning PMC PEB -1http://www.wiwynn.com8F, 90, Sec.1, Xintai 5th Rd., Xizhi Dist.,New Taipei City 22102, Taiwan (R.O.C.)
Title
Size Document Number R e v
Date: Sheet o f
Lightning PMC PEB -11I2C/SMBUS DIAGRAMCustom9 60Friday, March 31, 2017Lightning PMC PEB -1http://www.wiwynn.com8F, 90, Sec.1, Xintai 5th Rd., Xizhi Dist.,New Taipei City 22102, Taiwan (R.O.C.)



5
5
4
4
3
3
2
2
1
1
D D
C C
B B
A A
CLK
CS
L：A  to  B1  (BMC)H：A  to  B2  (I210)  default
SI
SOI2C_MUX_3AI2C_MUX_1AI2C_MUX_4ABUS_SW_OE#P3V3_I2C_MUXSPI_FLASH_SELECT_RI2C_MUX_2ASPI_FLASH_SELECTP3V3_STBYP3V3_STBYP3V3_STBYNVM_CS_N_R 44NVM_SK_R 44NVM_SO_R 44NVM_SI_R 44I210_SK_R44I210_CS_N_R44I210_SI_R44I210_SO_R44SPICS0_N13SPICK13SPIDO13SPIDI13SPI_FLASH_SELECT14
Title
Size Document Number R e v
Date: Sheet o f
Lightning PMC PEB -11SPI MUXA310 60Friday, March 31, 2017Lightning PMC PEB -1http://www.wiwynn.com8F, 90, Sec.1, Xintai 5th Rd., Xizhi Dist.,New Taipei City 22102, Taiwan (R.O.C.)
Title
Size Document Number R e v
Date: Sheet o f
Lightning PMC PEB -11SPI MUXA310 60Friday, March 31, 2017Lightning PMC PEB -1http://www.wiwynn.com8F, 90, Sec.1, Xintai 5th Rd., Xizhi Dist.,New Taipei City 22102, Taiwan (R.O.C.)
Title
Size Document Number R e v
Date: Sheet o f
Lightning PMC PEB -11SPI MUXA310 60Friday, March 31, 2017Lightning PMC PEB -1http://www.wiwynn.com8F, 90, Sec.1, Xintai 5th Rd., Xizhi Dist.,New Taipei City 22102, Taiwan (R.O.C.)
R48 0R2J-2-GPNOPOP12
R53 0R2J-2-GPNOPOP12
R47 0R2J-2-GPNOPOP12
R6564K7R2F-GP
NOPOP
12
R60210KR2F-2-GP
NOPOP12
U50SN74CBTLV3257RGYR-1-GP
NOPOP
S11B121B231A42B152B262A7GND83A93B2103B1114A124B2134B114OE#15VCC16GND17
C371SCD1U16V2KX-3GP
NOPOP
12
R50 0R2J-2-GPNOPOP12
R49 0R2J-2-GPNOPOP12
R6584K7R2F-GP
NOPOP
12
R330R3J-0-U-GP
NOPOP
12
R6954K7R2F-GP
NOPOP
12



5
5
4
4
3
3
2
2
1
1
D D
C C
B B
A A
ADD=1010000 (0xA0)
EEPROM
ADD=10011000 (0x98)
TEMP SENSOR 1
ADD=1001010 (0x94)
TEMP SENSOR 2
ADD=1001101 (0x9A)
TEMP SENSOR 3
TEMP_1_A1TEMP_SENSOR_DXNTEMP_SENSOR_DXN_BJTTEMP_SENSOR_DXP_RTEMP_SENSOR_CTEMP_SENSOR_DXPTEMP_1_A0EEPROM_A2_REEPROM_WPEEPROM_A0_REEPROM_A1_RTEMP_SENSOR_DXPTEMP_1_SCLTEMP_1_SDAEEPROM_SCLEEPROM_SDA
Temp_2_A0Temp_2_SCLTemp_2_ALERTTemp_2_A2Temp_2_A1Temp_3_A0Temp_3_SCLTemp_3_ALERTTemp_3_A2Temp_3_A1Temp_2_SDATemp_3_SDATEMP_SENSOR_DXNP3V3_STBYP3V3_STBYP3V3_STBYP3V3_STBYP3V3_STBYP3V3_STBYP3V3_STBY
BMC_I2C5_D_PEB_SDA11,21,23,31,36,46BMC_I2C5_D_PEB_SCL11,21,23,31,36,46
BMC_I2C5_D_PEB_SDA 11,21,23,31,36,46BMC_I2C5_D_PEB_SCL 11,21,23,31,36,46BMC_I2C5_D_PEB_SDA11,21,23,31,36,46BMC_I2C5_D_PEB_SCL11,21,23,31,36,46BMC_I2C5_D_PEB_SDA11,21,23,31,36,46BMC_I2C5_D_PEB_SCL11,21,23,31,36,46
Title
Size Document Number R e v
Date: Sheet o f
Lightning PMC PEB -11AST2400 I2C DEVICEA311 60Friday, March 31, 2017Lightning PMC PEB -1http://www.wiwynn.com8F, 90, Sec.1, Xintai 5th Rd., Xizhi Dist.,New Taipei City 22102, Taiwan (R.O.C.)
Title
Size Document Number R e v
Date: Sheet o f
Lightning PMC PEB -11AST2400 I2C DEVICEA311 60Friday, March 31, 2017Lightning PMC PEB -1http://www.wiwynn.com8F, 90, Sec.1, Xintai 5th Rd., Xizhi Dist.,New Taipei City 22102, Taiwan (R.O.C.)
Title
Size Document Number R e v
Date: Sheet o f
Lightning PMC PEB -11AST2400 I2C DEVICEA311 60Friday, March 31, 2017Lightning PMC PEB -1http://www.wiwynn.com8F, 90, Sec.1, Xintai 5th Rd., Xizhi Dist.,New Taipei City 22102, Taiwan (R.O.C.)
R5854K7R2F-GP
NOPOP
12
 R5894K7R2F-GP
NOPOP
12
R1954K7R2F-GP12
U1624LC64-I-SN-GPA01A12A23VSS4SDA5SCL6WP7VCC8
C326SCD1U16V2KX-3GP
NOPOP
12
R1910R2J-2-GP12
 R1644K7R2F-GP
NOPOP
12
R1590R2J-2-GP
NOPOP12
R1774K7R2F-GP
NOPOP
12
TP171TPAD32-GP1
 R1620R2J-2-GP
NOPOP12
 R1604K7R2F-GP
NOPOP
12
R1900R2J-2-GP12
R1938K2R2J-3-GP
NOPOP
12
 R1894K7R2F-GP
NOPOP
12
R5880R2J-2-GP
NOPOP12
R5870R2J-2-GP
NOPOP12
R1928K2R2J-3-GP
NOPOP
12
R5914K7R2F-GP
NOPOP
12
C153SC100P50V2JN-3GP
NOPOP
12
R5904K7R2F-GP
NOPOP
12
R5924K7R2F-GP
NOPOP
12
R201 49D9R2D-GP12
 R1614K7R2F-GP
NOPOP
12
U136TMP75AIDGKR-GP
NOPOP
SDA1SCL2ALERT3GND4A25A16A07V+8
R1784K7R2F-GP
NOPOP
12
 C151SCD1U16V2KX-3GP12
R1988K2R2J-3-GP12
 R202 49D9R2D-GP12
 R1654K7R2F-GP
NOPOP
12
R5864K7R2F-GP
NOPOP
12
R1884K7R2F-GP
NOPOP
12
R2030R2J-2-GP
NOPOP
12
R208 0R2J-2-GP12
R1998K2R2J-3-GP12
 R1964K7R2F-GP12
R204 0R2J-2-GP12
U134TMP75AIDGKR-GP
NOPOP
SDA1SCL2ALERT3GND4A25A16A07V+8
Q4PN2907AL-T92-K-GPCBE
C152SCD1U16V2JX-1-GP12
R1948K2R2J-3-GP
NOPOP
12
TP166TPAD32-GP1
R1978K2R2J-3-GP12
 U15TMP421AIDCNRG4-GPDXP1DXN2A13A04GND5SDA6SCL7V+8
C328SCD1U16V2KX-3GP
NOPOP
12
R212 0R2J-2-GP12
R2008K2R2J-3-GP12



5
5
4
4
3
3
2
2
1
1
D D
C C
B B
A A
DDR3 Vref
H : PLX versionL : PMC version
Co-lay
PVT 20161103
PVT 20161103BMC_I2C10_8536_SDABMC_I2C10_8536_SCLBMC0_SMB6_DATBMC0_SMB6_CLKBMC_I2C12_MINI6_SDA_SBMC_I2C12_MINI6_SCL_SBMC_I2C11_MINI5_SDA_SBMC_I2C11_MINI5_SCL_SBMC0_SMB4_CLKBMC0_SMB4_DATBMC0_SMB5_CLKBMC0_SMB5_DATMemA_13MemA_14MemODTMemCSNMemRASNMemCASNMemBA_0MemBA_1MemBA_2MemDM_0MemDM_1MemWENMemCK_NMemCKEMemA_10MemA_11MemA_12MemA_0MemA_1MemA_2MemA_3MemA_4MemA_5MemA_6MemA_7MemA_8MemA_9BMC_I2C8_CLKBUF1_SDABMC_I2C8_CLKBUF1_SCLBMC0_SMB7_CLKBMC0_SMB7_DATBMC0_SMB8_DATBMC0_SMB8_CLKBMC0_SMB9_DATBMC0_SMB9_CLKTP_LPC_CPU_FRAME_NTP_BMC0_LPC_LAD0TP_BMC0_LPC_LAD1TP_BMC0_LPC_LAD2TP_BMC0_LPC_LAD3TP_LPC_CPU_CLKOUT0TP_IRQ_CPU_SERIALDDR_VREFMemDQ_5MemDQ_6MemDQ_7MemDQ_8MemDQ_9MemDQ_10MemDQ_11MemDQ_12MemDQ_13MemDQ_14MemDQ_15MemDQ_0MemDQ_1MemDQ_2MemDQ_3MemDQ_4MemDQS_P1MemDQS_N1MemDQS_P0MemDQS_N0BMC0_SMB14_CLKBMC0_SMB14_SDABMC_I2C14_MINI8_SDA_SBMC_I2C14_MINI8_SCL_SBMC_I2C13_MINI7_SDA_SBMC_I2C13_MINI7_SCL_SBMC_I2C9_CLKBUF2_SDABMC_I2C9_CLKBUF2_SCLBMC0_SCL13_RBMC0_SDA13_RI2C_MUX_RESET_PEB_RPMC_PLX_BOARDPMC_PLX_BOARDGPIOB1PE1_PERST#MemA_13MemA_14PD_ZQDDR_VREFMemA_11MemA_10MemA_12MemA_1MemA_0MemA_3MemA_2MemA_6MemA_5MemA_4MemA_8MemA_7MemA_9MemCKEMemCASNMemRASNMemWENMemCSNBMC_DDR3_RST_NDDR_VREFBMC_I2C3_MINI3_SDA_SBMC_I2C3_MINI3_SCL_SBMC_I2C5_D_PEB_DEVICE_SDABMC_I2C5_D_PEB_DEVICE_SCLBMC_I2C4_MINI4_SDA_SBMC_I2C4_MINI4_SCL_SBMC_I2C1_MINI1_SDA_SBMC_I2C1_MINI1_SCL_SBMC_I2C7_B_DPB_SDABMC_I2C7_B_DBP_SCLBMC_I2C6_C_FCB_SDABMC_I2C6_C_FCB_SCLBMC_I2C2_MINI2_SDA_SBMC_I2C2_MINI2_SCL_SBMC_PEREXTBMC_REFCLK_PBMC_REFCLK_N
I2C_MUX_RESET_PEB
BMC_PETXPTP_GPIOD5TP_GPIOD0TP_GPIOD4TP_GPIOD3TP_GPIOD1TP_GPIOD2TP_GPIOD7TCA9554_INT_N_RBMC_PETXN
BMC_RESET#_DDR3
I2C1_LS_G2I2C1_LS_G1I2C2_LS_G2I2C2_LS_G1I2C3_LS_G2I2C3_LS_G1I2C4_LS_G2I2C4_LS_G1I2C5_LS_G2I2C5_LS_G1I2C6_LS_G2I2C6_LS_G1I2C7_LS_G2I2C7_LS_G1I2C8_LS_G2I2C8_LS_G1
BMC_I2C2_MINI2_SDA_S
BMC_I2C14_MINI8_SDA_S
BMC_I2C1_MINI1_SCL_SBMC_I2C2_MINI2_SCL_SBMC_I2C3_MINI3_SCL_SBMC_I2C4_MINI4_SCL_SBMC_I2C11_MINI5_SCL_SBMC_I2C12_MINI6_SCL_SBMC_I2C13_MINI7_SCL_SBMC_I2C14_MINI8_SCL_S
BMC_I2C1_MINI1_SDA_SBMC_I2C3_MINI3_SDA_SBMC_I2C4_MINI4_SDA_SBMC_I2C11_MINI5_SDA_SBMC_I2C12_MINI6_SDA_SBMC_I2C13_MINI7_SDA_SBMC_MIOZMemDQ_11MemDQ_13MemDQ_12MemDQ_14MemDQ_15MemDQ_10MemDQ_9MemDQ_8MemDQ_6MemDQ_2MemDQ_4MemDQ_7MemDQ_3MemDQ_1MemDQ_5MemDQ_0MemDM_0MemDM_1MemDQS_P1MemDQS_N1MemDQS_P0MemDQS_N0MemCK_PMemCK_NMemBA_0MemBA_2MemBA_1BMC0_SMB10_CLKBMC0_SMB10_DAT
MemODT
BMC_I2C4_MINI4_SCL_SBMC_I2C4_MINI4_SDA_SBMC0_SMB4_CLKBMC0_SMB4_DATBMC0_SMB2_CLKBMC0_SMB2_DATBMC0_SMB3_CLKBMC0_SMB3_DATBMC0_SMB1_CLKBMC0_SMB1_DATBMC_I2C1_MINI1_SDA_SBMC_I2C2_MINI2_SCL_SBMC_I2C2_MINI2_SDA_SBMC_I2C1_MINI1_SCL_SBMC_I2C3_MINI3_SCL_SBMC_I2C3_MINI3_SDA_SLAN_SMB_ALERT_N_RBMC_I2C12_MINI6_SDA_SBMC_I2C12_MINI6_SCL_SBMC0_SDA11_RBMC0_SCL11_RBMC0_SCL12_RBMC0_SDA12_RBMC_I2C13_MINI7_SDA_SBMC_I2C13_MINI7_SCL_SPE1_PERST#_BMCTP_GPIOB2LAN_SMB_ALERT_N
BMC_REFCLK_PBMC_REFCLK_NBMC_REFCLK_PBMC_REFCLK_NP1V53_STBYP3V3_STBYP1V53_STBY
P3V3_STBYP3V3_STBYP3V3_STBYP3V3_STBYP3V3_STBYP3V3_STBYP3V3_STBYP3V3_STBYP3V3_STBYP3V3_STBYP3V3_STBYP3V3_STBYP3V3_STBYP3V3_STBYP3V3_STBYP3V3_STBYP1V53_STBYP3V3_STBYP3V3_STBYP3V3_STBYBMC_I2C6_C_FCB_SDA 21BMC_I2C5_D_PEB_DEVICE_SDA 21,26BMC_I2C7_B_DBP_SCL 21BMC_I2C6_C_FCB_SCL 21BMC_I2C5_D_PEB_DEVICE_SCL 21,26BMC_I2C8_CLKBUF1_SDA 21,29BMC_I2C8_CLKBUF1_SCL 21,29BMC_I2C7_B_DPB_SDA 21BMC_I2C9_CLKBUF2_SDA 21BMC_I2C9_CLKBUF2_SCL 21BMC_I2C10_8536_SDA21BMC_I2C10_8536_SCL21PCIE_TX_N7635PCIE_RX_P76 35PCIE_TX_P7635
BMC_DDR3_RST_N14
PEWAKE#37BMC_PERST#_R41,44PCIE_RX_N76 35BMC_RESET#_DDR3 14BMC_I2C1_MINI1_SCL 28BMC_I2C2_MINI2_SCL 28BMC_I2C3_MINI3_SCL 28BMC_I2C4_MINI4_SCL 28BMC_I2C11_MINI5_SCL 29BMC_I2C12_MINI6_SCL 29BMC_I2C13_MINI7_SCL 29BMC_I2C14_MINI8_SCL 29
BMC_I2C1_MINI1_SDA28BMC_I2C2_MINI2_SDA28BMC_I2C3_MINI3_SDA28BMC_I2C4_MINI4_SDA28BMC_I2C11_MINI5_SDA29BMC_I2C12_MINI6_SDA29BMC_I2C13_MINI7_SDA29BMC_I2C14_MINI8_SDA29LAN_SMB_ALERT_N 44LAN_SMB_CLK 44LAN_SMB_DAT 44BMC_I2C14_MINI8_SDA_S43BMC_I2C14_MINI8_SCL_S43PE1_PERST# 32BMC_I2C1_MINI1_SDA_S 28BMC_I2C1_MINI1_SCL_S 28BMC_I2C11_MINI5_SDA_S29BMC_I2C11_MINI5_SCL_S29I2C_MUX_RESET_PEB27TCA9554_INT_N29PCIE_REFCLK_S5_P36PCIE_REFCLK_S5_N36
Title
Size Document Number Rev
Date: Sheet o f
Lightning PMC PEB -11AST2400 I2C DDR LPCCustom12 60Friday, March 31, 2017Lightning PMC PEB -1http://www.wiwynn.com8F, 90, Sec.1, Xintai 5th Rd., Xizhi Dist.,New Taipei City 22102, Taiwan (R.O.C.)
Title
Size Document Number Rev
Date: Sheet o f
Lightning PMC PEB -11AST2400 I2C DDR LPCCustom12 60Friday, March 31, 2017Lightning PMC PEB -1http://www.wiwynn.com8F, 90, Sec.1, Xintai 5th Rd., Xizhi Dist.,New Taipei City 22102, Taiwan (R.O.C.)
Title
Size Document Number Rev
Date: Sheet o f
Lightning PMC PEB -11AST2400 I2C DDR LPCCustom12 60Friday, March 31, 2017Lightning PMC PEB -1http://www.wiwynn.com8F, 90, Sec.1, Xintai 5th Rd., Xizhi Dist.,New Taipei City 22102, Taiwan (R.O.C.)
R9024191R2F-GP12
R249 0R2J-2-GP12
R3234K7R2F-GP12
 R21 0R2J-2-GPNOPOP12
R4700R2J-2-GP12
 R4754K7R2F-GP12
R235100KR2F-L1-GP12
R234100KR2F-L1-GP12
R2934K7R2F-GP12
R60510KR2F-2-GP12
R904656R2F-1-GP12
 U132N7002DW-7F-GP123456TP2431
 R4722K2R2J-2-GP12
R40710KR2F-2-GP12
C181SCD1U16V2KX-3GP12
 R40 0R2J-2-GP
NOPOP
12
R3064K7R2F-GP12
R4710R2J-2-GP12
C286 SCD01U16V2KX-3GP12
C175SCD1U16V2KX-3GP12
 R466 0R2J-2-GP12
C179SCD01U25V2KX-3GP12
 R244 0R2J-2-GP12
R4394K7R2F-GP12TP3061
 R66 0R2J-2-GP
NOPOP
12
C170SC10U6D3V5KX-4GP12TP3081
R642 0R2J-2-GP12
R247 0R2J-2-GP12
R9045470R2F-GP12
 R460 0R2J-2-GP12
 R3284K7R2F-GP12
R4414K7R2F-GP12
C177SCD01U25V2KX-3GP12
 R462 0R2J-2-GP12
 R65 0R2J-2-GPNOPOP12
C172SCD1U16V2KX-3GP12
U18K4B2G1646F-BCK0-GPZQL8VDDB2VDDD9VDDG7VDDK2VDDK8VDDN1VDDN9VDDR1VDDR9A10/APL7A3N2A0N3A12/BC#N7A5P2A2P3A1P7A4P8A7R2A9R3A11R7A6R8A8T8VSSA9VSSB3VSSE1VSSG8VSSJ2VSSJ8VSSM1VSSM9VSSP1VSSP9VSST1VSST9VSSQB1VSSQB9VSSQD1VSSQD8VSSQE2VSSQE8VSSQF9VSSQG1VSSQG9VDDQC1VDDQC9VDDQD2VDDQE9VDDQF1VDDQH2VDDQH9VDDQA1VDDQA8RAS#J3CAS#K3WE#L3DQU0D7DQU1C3DQU2C8DQU3C2DQU4A7DQU5A2DQU6B8DQU7A3DQL0E3DQL1F7DQL2F2DQL3F8DQL4H3DQL5H8DQL6G2DQL7H7VREFDQH1VREFCAM8BA0M2BA1N8BA2M3CKJ7CK#K7CKEK9DMLE7DMUD3DQSLF3DQSL#G3DQSUC7DQSU#B7NC#T7T7A13T3NC#M7M7NC#L9L9NC#L1L1NC#J9J9NC#J1J1ODTK1CS#L2RESET#T2
R19 0R2J-2-GP
NOPOP
12
PCI-Express
DDR2/DDR3
LPC
I2CSD/SDIOGPIO
1 OF 4
U40AAST2400A1-GPPERST#K19PEWAKE#J22PERXPF21PERXNF22PEREFCLKPG22PEREFCLKNG21PEREXTD20PETXPE22PETXNE21MDQ0W12MDQ1V12MDQ2AB11MDQ3AA11MDQ4Y11MDQ5W11MDQ6V11MDQ7Y10MDQ8V10MDQ9AB9MDQ10AA9MDQ11Y9MDQ12W9MDQ13V9MDQ14Y8MDQ15W8MDQS0AB10MDQS1AA8MDQS0#AA10MDQS1#AB8MCKAB12MCK#AA12MCKEY12MODTV14MCS#AA13MRAS#W13MCAS#AB13MWE#Y13MDM0W10MDM1V8MBA0W14MBA1AA14MBA2Y14MA0AB14MA1W15MA2V15MA3Y16MA4AB15MA5W16MA6AA15MA7AB18MA8AB16MA9AA17MA10Y15MA11AA16MA12W17MA13Y17MA14AB17MIOZV16MVREFV13LCLKB20LFRAME#A21LSIRQE17LAD0B21LAD1A22LAD2F19LAD3C19SCL1K21SDA1K22SCL2J19SDA2J18GPIOQ0_SCL3D3GPIOQ1_SDA3C2GPIOQ2_SCL4B1GPIOQ3_SDA4F5GPIOK0_SCL5E3GPIOK1_SDA5D2GPIOK2_SCL6C1GPIOK3_SDA6F4GPIOK4_SCL7E2GPIOK5_SDA7D1GPIOK6_SCL8G5GPIOK7_SDA8F3GPIOQ4_SCL14H4GPIOQ5_SDA14H3GPIOQ6H2GPIOQ7H1GPIOC0_SD1CLK_SCL10C4GPIOC1_SD1CMD_SDA10B3GPIOC2_SD1DAT0_SCL11A2GPIOC3_SD1DAT1_SDA11E5GPIOC4_SD1DAT2_SCL12D4GPIOC5_SD1DAT3_SDA12C3GPIOC6_SD1CD#_SCL13B2GPIOC7_SD1WP#_SDA13A1GPIOA4_TIMER5_SCL9C5GPIOA5_TIMER6_SDA9B4GPIOB0_SALT1J21GPIOB1_SALT2J20GPIOB2_SALT3H18GPIOB3_SALT4F18GPIOD0_SD2CLKA18GPIOD1_SD2CMDD16GPIOD2_SD2DAT0B17GPIOD3_SD2DAT1A17GPIOD4_SD2DAT2C16GPIOD5_SD2DAT3B16GPIOD6_SD2CD#A16GPIOD7_SD2WP#E15
R2310KR2F-2-GP
NOPOP
12
R4574K7R2F-GP12
R243 0R2J-2-GP12
R262 0R2J-2-GPNOPOP12
 R3304K7R2F-GP12
R5054K7R2F-GP12
R4334K7R2F-GP12
R2944K7R2F-GP12
U372N7002DW-7F-GP123456
R4374K7R2F-GP12
R246 0R2J-2-GP12TP2421
 U82N7002DW-7F-GP123456
C176SCD1U16V2KX-3GP12
 R510 0R2J-2-GP12
R5994K7R2F-GP12
R242 0R2J-2-GP12
R5784K7R2F-GP12
R6014K7R2F-GP12
R261 0R2J-2-GPNOPOP12
C184SCD1U16V2KX-3GP12
 R4922K2R2J-2-GP12
R7080R2J-2-GP12
 R5814K7R2F-GP12
C171SCD1U16V2KX-3GP12
 R5224K7R2F-GP12
R488 0R2J-2-GP12
 R2954K7R2F-GP12
R16 0R2J-2-GPNOPOP12
R251 0R2J-2-GP12
R248240R2F-1-GP12
 R64 0R2J-2-GP
NOPOP
12
C182SCD1U16V2KX-3GP12
 R4214K7R2F-GP12
R18 0R2J-2-GPNOPOP12
R731 0R2J-2-GP
NOPOP
12
C287 SCD01U16V2KX-3GP12
 R2964K7R2F-GP12
R245 0R2J-2-GP12
C185SCD1U16V2KX-3GP12
R15 0R2J-2-GP
NOPOP
12
R7070R2J-2-GP12
 U122N7002DW-7F-GP123456
R9044470R2F-GP12
 R3124K7R2F-GP12
R461 0R2J-2-GP12
R238 0R2J-2-GP12
R2311KR2F-3-GP12
 R4364K7R2F-GP12
R4690R2J-2-GP12
R904756R2F-1-GP12
 R4384K7R2F-GP12
 R39 0R2J-2-GPNOPOP12
R3074K7R2F-GP12
R542 0R2J-2-GP12
R258100KR2F-L1-GP12
R73 33R1J-GPNOPOP12
 U282N7002DW-7F-GP123456TP3051
 R26 0R2J-2-GPNOPOP12
R3134K7R2F-GP12
R4404K7R2F-GP12
C183SCD1U16V2KX-3GP12
R237100KR2F-L1-GP12
R20100R2F-L1-GP-U12
 U232N7002DW-7F-GP123456
R3254K7R2F-GP12
R490 0R2J-2-GP12
R240 0R2J-2-GP12TP3071
R531 0R2J-2-GP12
 R3094K7R2F-GP12
R4564K7R2F-GP12
C239SCD1U16V2KX-3GP12
R230 4K7R2F-GP12
R2321KR2F-3-GP12
R259100KR2F-L1-GP12
 R17 0R2J-2-GP
NOPOP
12
R5794K7R2F-GP12
R3314K7R2F-GP12
R4224K7R2F-GP12
C178SCD1U16V2KX-3GP12
 R465 0R2J-2-GP12
C180SC1U10V2KX-4-GP12
R233100KR2F-L1-GP12
 R52 0R2J-2-GPNOPOP12
R239 0R2J-2-GP12TP2441
R241 0R2J-2-GP12TP1071
R4114K7R2F-GPNOPOP12
R565 0R2J-2-GP12
R3144K7R2F-GPNOPOP12
 R32 0R2J-2-GP
NOPOP
12
U322N7002DW-7F-GP123456
R467 0R2J-2-GP12
R5984K7R2F-GP12
C729 SCD22U10V2KX-1GP12
R67 0R2J-2-GPNOPOP12
R3274K7R2F-GP12
C173SCD1U16V2KX-3GP12
 R5244K7R2F-GP12
R6004K7R2F-GP12
R3004K7R2F-GP12
R487 0R2J-2-GP12
R5300R2J-2-GP12
 R22 0R2J-2-GP
NOPOP
12
R236100KR2F-L1-GP12
 U392N7002DW-7F-GP123456
R5804K7R2F-GP12
C730 SCD22U10V2KX-1GP12
R70910KR2F-2-GPNOPOP12
R5204K7R2F-GP12
 R4084K7R2F-GP12
R1202 274R2F-GP12



5
5
4
4
3
3
2
2
1
1
D D
C C
B B
A A
BMC Flash SKT
BMC SPI Flash
BMC UART header
PMC UART header
BMC ADD header
JP4 header JP6 header
1-2 (Default)
2-3
1-2 (Default)
2-3 Secure Flash
Secure Flash SKT
Default : 1-2
Close to U40
Co-lay
Co-lay
Co-lay
Co-lay
Default : 1-2
Connection
1-2
JP4
1 Leopard to 1 Lightning
JP6
1 Leopard to 2 Lightning
1 Leopard to 3 Lightning
1 Leopard to 4 Lightning
1-2
2-3 1-2
1-2 2-3
2-32-3
TP_GPIOH3TP_GPIOH4TP_GPIOH5RMII0_BMC_C_PHY_TXD1RMII0_BMC_C_TX_ENRMII0_BMC_C_PHY_TXD0RMII0_BMC_C_CRS_DVPU_IBMC_BT_HOLD_NFLA_CS1_RROMD2_RROMD0_RFLA_WPNROMD1_RTP_GPIOH6TP_GPIOH7BMC_RXD5_RRMII_BMC_RX_ERBMC_TXD5_RRMII0_PHY_BMC_RXCTL0ROMA5ROMA4ROMA3ROMA2ROMA1ROMA0ROMA10ROMA9ROMA8ROMA7ROMA6ROMA14ROMA13ROMA12ROMA11ROMA20ROMA19ROMA18ROMA17ROMA16ROMA15ROMA22ROMA21ROMA23GPIOR5_RROMD1ROMD2ROMD3ROMD4ROMD5ROMD6ROMD7ROMD0GPIOM0_I210_PERST_NTP_GPIOE7TP_GPIOE6PWGD_P0V9_E_PG_RTP_GPIOT6TP_GPIOE1TP_GPIOE2TP_GPIOE3BMC_ADD1_RBMC_ADD2_RTP_GPIOU3TP_GPIOA6TP_GPIOA7TP_GPIOT7CLK_50M_BMC_NCSI_RBMC_RXCK_RCLK_50M_BMC0RMII_PHY_BMC_RXD0RMII_PHY_BMC_RXD1RMII_BMC_PHY_TXD0RMII_BMC_PHY_TXD1
BMC_RXD5BMC_TXD5
GPIOH0GPIOH2_RGPIOH2FLA1_WPNBMC_ADD1BMC_ADD2
PMC_R_RXD5PMC_R_TXD5BMC_ADD1BMC_ADD1_PWRBMC_ADD1_GNDBMC_ADD2_PWRBMC_ADD2_GNDBMC_ADD2CBL_PRSNT_N_1CBL_PRSNT_N_3CBL_PRSNT_N_5CBL_PRSNT_N_7CBL_PRSNT_N_2CBL_PRSNT_N_4CBL_PRSNT_N_6CBL_PRSNT_N_8BMC_R_TXD5BMC_R_RXD5TP_GPIOI1TP_GPIOI2TP_GPIOI0SPIDI_RSPICS0_N_RSPICK_RSPIDO_RTP_GPIOV6TP_GPIOV7TP_GPIOV3TP_GPIOV4TP_GPIOV5TP_GPIOU2TP_GPIOU0TP_GPIOU1GPIOR4_BMC_INT_N_RGPIOR2_RGPIOR1_RGPIOS5_RGPIOR3_RTP_GPIOS4FLA_CS1
BMC_ID_LEDFLA_CS
FLA_CS1_R
SEC_SPI_HOLD_NFLA_CS_RROMD0_RFLA1_WPNROMD1_RWP_EnableWP_DisableSEC_RST_N_R
U19_PERST_NU19_PERST_NROMD2
ROMD2ROMD2_SEC
FLA_CS_RFLA_CS
BMC_TXD5_RBMC_TXD5BMC_RXD5BMC_RXD5_RBMC_RXD5_RFLA1_WPNFLA1_WPN_R
BMC_CPU_DISFLA_CS_RBMC_CPU_EN
U19_PERST_NROMD0_RROMD1_RROMD2_RTP_RGMIICKBMC_TXD5MBP_UART_TXFLA_WPNPU_IBMC_BT_HOLD_NFLA_CS1_RFLA_WPN
SEC_RST_N_RFLA_CS_RROMD0_RROMD1_RROMD2_SECFLA1_WPNSEC_SPI_HOLD_NBMC_TXD5_RP5V_STBYP5V_STBYP3V3_STBYP3V3_STBYP3V3_STBYP3V3_STBYP3V3_STBYP3V3_STBY
P3V3_STBYP3V3_STBYP3V3_STBYP3V3_STBYP3V3_STBYP3V3_STBYP3V3_STBYP3V3_STBY
P3V3_STBY
P3V3_STBY
P3V3_STBYP3V3_STBYP3V3_STBYP3V3_STBYP3V3_STBYP3V3_STBY
P3V3_STBYRMII_BMC_PHY_TXD0 44RMII_BMC_PHY_TXD1 44RMII_BMC_TX_EN 44RMII_PHY_BMC_RXD044RMII_PHY_BMC_RXD144RMII_BMC_CRS_DV44ROMD416ROMA[23..0] 16ROMD316ROMD216ROMD716ROMD616ROMD516CLK_50M_BMC044BMC_RXD525 BMC_TXD5 25BMC_ID_LED22P0V9_E_PG53CLK_50M_BMC_NCSI44EXP_SMART_RX 25,37EXP_SMART_TX 25,37
CBL_PRSNT_N_729CBL_PRSNT_N_829CBL_PRSNT_N_629CBL_PRSNT_N_529CBL_PRSNT_N_328CBL_PRSNT_N_428CBL_PRSNT_N_228CBL_PRSNT_N_128 BMC_SSD_RST#9 32BMC_SSD_RST#11 32BMC_SSD_RST#12 32BMC_SSD_RST#7 32BMC_SSD_RST#8 32BMC_SSD_RST#10 32BMC_SSD_RST#13 32BMC_SSD_RST#2 32BMC_SSD_RST#4 32BMC_SSD_RST#5 32BMC_SSD_RST#0 32BMC_SSD_RST#1 32BMC_SSD_RST#6 32BMC_SSD_RST#14 32BMC_SSD_RST#3 32SPICS0_N 10SPICK 10SPIDO 10SPIDI 10BMC_I210_PERST_N 44
FM_BMC_RESET_N13,14,26,44
FM_BMC_RESET_N13,14,26,44BMC_INT_N 43TRAY_ID243TRAY_ID143TRAY_ID043 TRAY_POWER_CRIT_N 43BP_PRSNT_N43ROMD0_R16ROMD1_R16
MBP_UART_RX43 MBP_UART_TX 43
Title
Size Document Number R e v
Date: Sheet o f
Lightning PMC PEB -11AST2400 UART LAN SPICustom13 60Friday, March 31, 2017Lightning PMC PEB -1http://www.wiwynn.com8F, 90, Sec.1, Xintai 5th Rd., Xizhi Dist.,New Taipei City 22102, Taiwan (R.O.C.)
Title
Size Document Number R e v
Date: Sheet o f
Lightning PMC PEB -11AST2400 UART LAN SPICustom13 60Friday, March 31, 2017Lightning PMC PEB -1http://www.wiwynn.com8F, 90, Sec.1, Xintai 5th Rd., Xizhi Dist.,New Taipei City 22102, Taiwan (R.O.C.)
Title
Size Document Number R e v
Date: Sheet o f
Lightning PMC PEB -11AST2400 UART LAN SPICustom13 60Friday, March 31, 2017Lightning PMC PEB -1http://www.wiwynn.com8F, 90, Sec.1, Xintai 5th Rd., Xizhi Dist.,New Taipei City 22102, Taiwan (R.O.C.)
SCN8JWT-CON4-S24-GP1234TP2701
 U45SN74AUP1T97DCKR-GP
NOPOP
B1GND2A3Y4VCC5C6TP951
R2642K2R2J-2-GP12
 R415 0R2J-2-GPNOPOP12
C282SCD1U16V2KX-3GP12
R711 0R2J-2-GPNOPOP12TP3261
R154 4K7R2F-GP12
R639 0R2J-2-GP12
 R285 22R2J-2-GPNOPOP12
R42610KR2F-2-GP
NOPOP
12
R2672K2R2J-2-GP
NOPOP
12
 R288 47KR2F-GP
NOPOP
12
SKT5SKT-SPI16P-GP-U12345678161514131211109
R4730R2J-2-GP12
R156 4K7R2F-GP12
 R961300R2F-GP12
U53SN74LVC1G07DCKRG4-2-GP
NOPOP
GND3A2NC#11VCC5Y4
R286 0R2J-2-GPNOPOP12
R640 0R2J-2-GPNOPOP12
 R290 0R2J-2-GPNOPOP12
R942 0R2J-2-GP12
 R41410KR2F-2-GP
NOPOP
12
R279 0R2J-2-GP12
R148 4K7R2F-GP12
R155 4K7R2F-GP12
 C280SCD1U16V2KX-3GP12TP3271
R645 0R2J-2-GPNOPOP12
U19MX25L25635FMI-10G-GPDNU/SIO31VCC2CS#7SO/SIO18WP#/SIO29GND10SI/SIO015SCLK16RESET#3NC#44NC#55NC#66NC#1111NC#1212NC#1313NC#1414
SCN9JWT-CON4-S24-GP1234
 C283SCD01U16V2KX-3GP12
R733 0R2J-2-GP12
R9604K7R2F-GP12
R2650R2J-2-GP12
R9624K7R2F-GPNOPOP12
JP12PIN-CON3-S-GP123
U49SN74AUP1T97DCKR-GP
NOPOP
B1GND2A3Y4VCC5C6
R679 0R2J-2-GPNOPOP12
R647 0R2J-2-GP12
R945 0R2J-2-GP12
R941 0R2J-2-GP12
 R732 0R2J-2-GP12
R149 4K7R2F-GP12
R5674K7R2F-GP
NOPOP
12
R297810KR2F-2-GP
NOPOP
12
JP4PIN-CON3-S-GP123
 JP13PIN-CON3-S-GP123
JP6PIN-CON3-S-GP123
 R944100KR2F-L1-GP12
R684 0R2J-2-GPNOPOP12
R946 0R2J-2-GP12
R150 4K7R2F-GP12
R41810KR2F-2-GP
NOPOP
12
R442 0R2J-2-GPNOPOP12TP921
R6720R2J-2-GPNOPOP12
 R464 0R2J-2-GPNOPOP12
R417 10KR2F-2-GPNOPOP12
SC1307SCD1U16V2KX-3GP12
U52SN74LVC1G07DCKRG4-2-GP
NOPOP
GND3A2NC#11VCC5Y4
R6360R2J-2-GP12
R9314K7R2F-GP12TP2731
SC1308SCD1U16V2KX-3GP12 TP3241TP1561
R620 0R2J-2-GPNOPOP12TP2331TP971
R163 4K7R2F-GP12
R291 0R2J-2-GPNOPOP12
C279SCD1U16V2KX-3GP12
U36MX25L25635FMI-10G-GPDNU/SIO31VCC2CS#7SO/SIO18WP#/SIO29GND10SI/SIO015SCLK16RESET#3NC#44NC#55NC#66NC#1111NC#1212NC#1313NC#1414
R704 0R2J-2-GPNOPOP12TP2951
SKT3SKT-SPI16P-GP-U12345678161514131211109TP2271
R9634K7R2F-GP
NOPOP12
C281SCD1U16V2KX-3GP12TP2261TP931TP2171TP2961
R638 22R2F-1-GP12 TP1531TP1551
R5060R2J-2-GP12
 R444 0R2J-2-GPNOPOP12
C284SCD01U16V2KX-3GP12
 R5640R2J-2-GP12TP2981TP941
R705 0R2J-2-GPNOPOP12TP1541
R151 4K7R2F-GP12
R5070R2J-2-GP12
 R42010KR2F-2-GP
NOPOP
12TP2921
R7400R2J-2-GP12
R659 0R2J-2-GPNOPOP12 TP3251TP3021TP2201
 R4232K2R2J-2-GP12
R9684K7R2F-GP
NOPOP12TP2931
R5410R2J-2-GP12BMC NOR/NAND/SPISystem UART
BMC UART
MAC1
MAC2
System  SPI
2 OF 4
U40B
AST2400A1-GP
ROMA0R20ROMA1R21ROMA2_GPIOZ0_VPOB0R22ROMA3_GPIOZ1_VPOB1P18ROMA4_GPIOZ2_VPOB2P19ROMA5_GPIOZ3_VPOB3P20ROMA6_GPIOZ4_VPOB4P21ROMA7_GPIOZ5_VPOB5P22ROMA8_GPIOZ6_VPOB6M19ROMA9_GPIOZ7_VPOB7M20ROMA10_GPIOAA0_VPOG0M21ROMA11_GPIOAA1_VPOG1M22ROMA12_GPIOAA2_VPOG2L18ROMA13_GPIOAA3_VPOG3L19ROMA14_GPIOAA4_VPOG4L20ROMA15_GPIOAA5_VPOG5L21ROMA16_GPIOAA6_VPOG6T18ROMA17_GPIOAA7_VPOG7N18ROMA18_GPIOAB0_VPOR0N19ROMA19_GPIOAB1_VPOR1M18ROMA20_GPIOAB2_VPOR2N22ROMA21_GPIOAB3_VPOR3N20ROMA22_GPIOS6_VPOR4L22ROMA23_GPIOS7_VPOR5K18GPIOR4_ROMA24_VPOR6V21GPIOR5_ROMA25_VPOR7W22ROMCS0#R19GPIOR0_ROMCS1#V20GPIOR1_ROMCS2#W21GPIOR2_ROMCS3#Y22GPIOR3_ROMCS4#U19ROMOE#_GPIOS4R18ROMWE#_GPIOS5N21ROMD0T22ROMD1T21ROMD2T20ROMD3U22ROMD4_GPIOS0_VPODEU21ROMD5_GPIOS1_VPOHST19ROMD6_GPIOS2_VPOVSV22ROMD7_GPIOS3_VPOCLKU20GPIOH0_ROMD8_NCTS6A8GPIOH1_ROMD9_NDCD6C7GPIOH2_ROMD10_NDSR6B7GPIOH3_ROMD11_NRI6A7GPIOH4_ROMD12_NDTR6D7GPIOH5_ROMD13_NRTS6B6GPIOH6_ROMD14_TXD6A6GPIOH7_ROMD15_RXD6E7GPIOL0_NCTS1U1GPIOL1_NDCD1_VPIDET5GPIOL2_NDSR1_VPIODDU3GPIOL3_NRI1_VPIHSV1GPIOL4_NDTR1_VPIVSU4GPIOL5_NRTS1_VPICLKV2GPIOL6_TXD1_VPIB0W1GPIOL7_RXD1_VPIB1U5GPIOM0_NCTS2_VPIB2V3GPIOM1_NDCD2_VPIB3W2GPIOM2_NDSR2_VPIB4Y1GPIOM3_NRI2_VPIB5V4GPIOM4_NDTR2_VPIB6W3GPIOM5_NRTS2_VPIB7Y2GPIOM6_TXD2_VPIB8AA1GPIOM7_RXD2_VPIB9V5GPIOE0_NCTS3D15GPIOE1_NDCD3C15GPIOE2_NDSR3B15GPIOE3_NRI3A15GPIOE4_NDTR3E14GPIOE5_NRTS3D14GPIOE6_TXD3C14GPIOE7_RXD3B14GPIOF0_NCTS4D18GPIOF1_NDCD4_SIOPBI#B19GPIOF2_NDSR4_SIOPWRGDA20GPIOF3_NRI4_SIOPBO#D17GPIOF4_NDTR4B18GPIOF5_NRTS4_SIOSCI#A19GPIOF6_TXD4E16GPIOF7_RXD4C17RXD5G1TXD5H5RGMII1TXD3_GPIOT5A13RGMII1TXD2_GPIOT4E12RGMII1TXD1_RMII1TXD1_GPIOT3D12RGMII1TXD0_RMII1TXD0_GPIOT2C12RGMII1TXCTL_GPIOT1B12RGMII1TXCK_RMII1TXEN_GPIOT0A12RGMII1RXCK_RMII1RCLK_GPIOU4E11RGMII1RXCTL_GPIOU5D11RGMII1RXD0_RMII1RXD0_GPIOU6C11RGMII1RXD1_RMII1RXD1_GPIOU7B11RGMII1RXD2_RMII1CRSDV_GPIOV0A11RGMII1RXD3_RMII1RXER_GPIOV1E10RGMII2TXD3_GPIOU3D10RGMII2TXD2_GPIOU2C10RGMII2TXD1_RMII2TXD1_GPIOU1B10RGMII2TXD0_RMII2TXD0_GPIOU0A10RGMII2TXCTL_GPIOT7E9RGMII2TXCK_RMII2TXEN_GPIOT6D9RGMII2RXCK_RMII2RCLK_GPIOV2C9RGMII2RXCTL_GPIOV3B9RGMII2RXD0_RMII2RXD0_GPIOV4A9RGMII2RXD1_RMII2RXD1_GPIOV5E8RGMII2RXD2_RMII2CRSDV_GPIOV6D8RGMII2RXD3_RMII2RXER_GPIOV7C8RGMIICKB8GPIOR6_MDC1C6GPIOR7_MDIO1A5GPIOA6_TIMER7_MDC2A3GPIOA7_TIMER8_MDIO2D5GPIOI0_SYSCS#C22GPIOI1_SYSCKG18GPIOI2_SYSDOD19GPIOI3_SYSDIC20GPIOI4_SPICS0#_VBCS#B22GPIOI5_SPICK_VBCKG19GPIOI6_SPIDO_VBDOC18GPIOI7_SPIDI_VBDIE20TP961
R152 4K7R2F-GP12TP2411
R2662K2R2J-2-GP12
 R283 22R2J-2-GPNOPOP12
C274SCD1U16V2KX-3GP12
R9334K7R2F-GP12
 C186SCD1U16V2KX-3GP12
 R280 0R2J-2-GP12
R606 22R2F-1-GP12TP2661
R9324K7R2F-GP12 TP2181
 R9434K7R2F-GP12
R281 0R2J-2-GPNOPOP12
R685 0R2J-2-GPNOPOP12
R9344K7R2F-GP12
 R289 0R2J-2-GPNOPOP12
R153 4K7R2F-GP12



5
5
4
4
3
3
2
2
1
1
D D
C C
B B
A A
Revision EVT DVT PVT
010
100
000
BMC_FW_DET_BOARD_VER_0
BMC_FW_DET_BOARD_VER_1
BMC_FW_DET_BOARD_VER_2
PVT 20161103PVT 20161201
0
0
1
MP
TP_GPION5
JTAG_BMC_TRST_NBMC0_JTAG_RTCKFM_BMC_RESET_N
TP_GPIOO2BMC0_SRST_NBMC0_TACH13ADC_P1V26_BMCBMC0_ENTEST1OSC0_AS_CLKINOSC2_OUTOSC2_CONTDP_RST_N_RBMC0_LED_DR_R_LED0FAN_PWM_PCIe_BMCLED_DR_LED0LOW_HEX_1LOW_HEX_2ADC_P1V8_STBY_BMCADC0_12V_BMCADC_P1V53_BMCADC_P3V3_STBY_BMCADC_P5V_STBY_BMCADC_P0V9_BMCADC_P0V9_E_BMCEXP_TRAY_ID_BMCLOW_HEX_3PD_USB2VRESHIGH_HEX_0HIGH_HEX_1HIGH_HEX_2HIGH_HEX_3PEER_TRAY_BMCLOW_HEX_0TP_GPIOO4JTAG_BMC_TRST_NJTAG_BMC_TDOJTAG_BMC_TMSJTAG_BMC_TDIJTAG_BMC_TCKBMC0_JTAG_RTCKFM_TPM_PRES_N_RPECI0_RTP_BMC_GPIOJ4TP_BMC_GPIOJ5TP_BMC_GPIOJ6TP_BMC_GPIOJ7BMC_SELF_HW_RST_RDP_BMC_CPU_RST_N_RBMC_USB2_HDPBMC_USB2_HDNBMC_USB1_HDNBMC_USB1_HDPBMC_USB1_HDN2BMC_USB1_HDP2JTAG_BMC_TDIJTAG_BMC_TMSJTAG_BMC_TCKJTAG_BMC_TDOBMC_JTAG_L_EN_RTP_GPIOP6TP_GPIOO6TP_GPIOO7TP_GPIOP2TP_GPIOP0BMC_FW_DET_BOARD_VER_0BMC_FW_DET_BOARD_VER_1BMC_FW_DET_BOARD_VER_2TP_GPIOP1RST_BMC_EXTRST_N_RTP_GPIOB6TP_GPIOO1TP_GPIOO0TP_GPIOP4PEER_TRAY_RBMC_SELF_TRAYFCB_HW_REVISIONBMC_USB_EN_1DPB_HW_REVISIONBMC_SELF_TRAY_R
BMC_JTAG_L_ENBMC_JTAG_L_ENDACBDACGDACR
HB_OUT_BMCPEER_BMC_HBEXP_TRAY_IDTP_GPIOY3TP_GPIOB5FM_BMC_RESET#_BTN_D
PWM_EXP_A
RST_BMC_DDR3_R_NLED_DR_LED1TP_GPIOA3JTAG_BMC_TDIJTAG_BMC_TMSJTAG_BMC_TRST_NBMC0_JTAG_RTCKFM_BMC_RESET_NJTAG_BMC_TCKJTAG_BMC_TDOBMC_RESET#_DDR3_BUFFM_BMC_RESET_Q36_RFM_PCH_LAN1_DISABLE_N_RHOST_I2C_RESET_N_DFM_BMC_RESET_Q36U80_BTRAY_RESET_N_R
BMC_FW_DET_BOARD_VER_0BMC_FW_DET_BOARD_VER_1BMC_FW_DET_BOARD_VER_2P3V3_STBYP1V26_STBYP3V3_STBYP3V3_STBYP3V3_STBYP3V3_STBYP3V3_STBYP3V3_STBYP3V3_STBYP3V3_STBYP3V3_STBYP3V3_STBYP1V53_STBYP3V3_STBY
P3V3_STBY
P3V3_STBY
P3V3_STBYPEER_TRAY_R27FM_BMC_RESET_N13,14,26,44BMC_SELF_TRAY 27ADC_P1V53V17ADC_12V17ADC_P3V3_STBY17ADC_P5V_STBY17ADC_P1V8_STBY17ADC_P0V917ADC_P0V9_E17 FCB_HW_REVISION 27DPB_HW_REVISION 27LOW_HEX_0 25LOW_HEX_1 25LOW_HEX_2 25LOW_HEX_3 25HIGH_HEX_0 25HIGH_HEX_1 25HIGH_HEX_2 25HIGH_HEX_3 25DP_RST_N25,32HB_OUT_BMC24 LED_DR_LED1 22BMC_UART_SWITCH_125UART_COUNT25BMC_ENCLOSURE_LED22BMC_USB_EN_120PEER_BMC_HB27FM_BMC_RESET#_BTN32
PWM_EXP_A 27
BMC_DDR3_RST_N 12BMC_RESET#_DDR312
USB2_BMC_DP 28USB2_BMC_DN 28USB_P2_DP 20USB_P2_DN 20USB_P4_DP_BMC 29USB_P4_DN_BMC 29ADC_P1V2617 FM_BMC_RESET_N 13,14,26,44HOST_I2C_RESET_N28,29PWRGD_P1V26_STBY51,52RST_BMC_EXTRST_N 14,26BMC_SELF_HW_RST26FM_TPM_PRES_N26 FM_PCH_LAN1_DISABLE_N 44TRAY_RESET_N43SPI_FLASH_SELECT 10RST_BMC_EXTRST_N14,26EXP_TRAY_ID27
Title
Size Document Number R ev
Date: Sheet o f
Lightning PMC PEB -11AST2400 FAN ADC VGA JTAGCustom14 60Friday, March 31, 2017Lightning PMC PEB -1http://www.wiwynn.com8F, 90, Sec.1, Xintai 5th Rd., Xizhi Dist.,New Taipei City 22102, Taiwan (R.O.C.)
Title
Size Document Number R ev
Date: Sheet o f
Lightning PMC PEB -11AST2400 FAN ADC VGA JTAGCustom14 60Friday, March 31, 2017Lightning PMC PEB -1http://www.wiwynn.com8F, 90, Sec.1, Xintai 5th Rd., Xizhi Dist.,New Taipei City 22102, Taiwan (R.O.C.)
Title
Size Document Number R ev
Date: Sheet o f
Lightning PMC PEB -11AST2400 FAN ADC VGA JTAGCustom14 60Friday, March 31, 2017Lightning PMC PEB -1http://www.wiwynn.com8F, 90, Sec.1, Xintai 5th Rd., Xizhi Dist.,New Taipei City 22102, Taiwan (R.O.C.)
C3217SCD1U25V2KX-2-GP12
R8044K7R2F-GP12
 U25SN74LVC1G07DCKRG4-2-GPGND3A2NC#11VCC5Y4
R2574K7R2F-GP12
 C275SCD1U16V2KX-3GP12
G1TPAD-JTAG-7P-GP1234567
TP2191
R4934K7R2F-GP12
SR8534K75R2F-1-GP12
R537 0R2J-2-GP12TP2161
R3730R2J-2-GP12
R614 0R2J-2-GP12
 SR8494K75R2F-1-GP12
TP1731
 R56110KR2F-2-GP
NOPOP
12
R80050R2J-2-GP12TP1621TP1611
C264SCD22U16V2KX-GP12
TP2281
SR9444K75R2F-1-GP
NOPOP
12
R3150R2J-2-GP12
R3210R2J-2-GP12
 R5540R2J-2-GP12TP2401
 R3110R2J-2-GPNOPOP12
R4490R2J-2-GP12
U20574AHC1G08DCKR-GPA1B2GND3Y4VCC5
R255 4K7R2F-GP12
D1401RB551V30-GPKA
R225 4K7R2F-GP12
R3200R2J-2-GP12TP1781
OSC1OSC-48MHZ-28-GPOE1GND2OUTPUT3VDD4TP1451
 R4510R2J-2-GP12
R5840R2J-2-GP12
R80070R2J-2-GP12TP1801
R2974K7R2F-GP12
R4910R2J-2-GP12
TP2691TP1601TP3171TP1911
TP1721
R221 4K7R2F-GP12
 R5040R2J-2-GPNOPOP
12TP2211
R7994K7R2F-GP12
R5330R2J-2-GP12TP3191
D1402RB551V30-GPKA
R4500R2J-2-GP12
R5340R2J-2-GP12TP1591
R4894K7R2F-GP12TP2451
R228 4K7R2F-GP12
 R3100R2J-2-GP12TP2371
 R4520R2J-2-GP12
R5380R2J-2-GP12
R607 0R2J-2-GPNOPOP12
R299 0R2J-2-GP12
R8024K7R2F-GP12
D1403RB551V30-GP
NOPOP
KATP2311
R29810R2F-L-GP12
 SR8474K75R2F-1-GP
NOPOP
12TP2361TP3211TP2291
VGA
USB
PECI
FAN
ADC
JTAG
SGPIO
GPIO
MISC
3 OF 4
U40CAST2400A1-GPENTESTE4GPIOY3_SIOONCTRL#K20CLKINAB22SRST#W20DACBR4DACGR3DACRR2DDCCLK_GPIOJ6T2DDCDAT_GPIOJ7T1VGAHS_GPIOJ4T4VGAVS_GPIOJ5U2GPIOO0_TACH0_VPIG8V6GPIOO1_TACH1_VPIG9Y5GPIOO2_TACH2_VPIR0AA4GPIOO3_TACH3_VPIR1AB3GPIOO4_TACH4_VPIR2W6GPIOO5_TACH5_VPIR3AA5GPIOO6_TACH6_VPIR4AB4GPIOO7_TACH7_VPIR5V7GPION4_PWM4_VPIG4W5GPION5_PWM5_VPIG5Y4GPION6_PWM6_VPIG6AA3GPION7_PWM7_VPIG7AB2USB2AV33W18USB2AVSSY19USB2VRESAA20USB2_DP/USB2_HDPAB21USB2_DN/USB2_HDNAB20USB11_HDNJ2USB11_HDPJ1USB11_DP/USB11_HDP2K4USB11_DN/USB11_HDN2K3PECIAA21PECIVDDV19ADC0_GPIW0L5ADC1_GPIW1L4ADC2_GPIW2L3ADC3_GPIW3L2ADC4_GPIW4L1ADC5_GPIW5M5ADC6_GPIW6M4ADC7_GPIW7M3ADC8_GPIX0M2ADC9_GPIX1M1ADC10_GPIX2N5ADC11_GPIX3N4ADC12_GPIX4N3ADC13_GPIX5N2ADC14_GPIX6N1ADC15_GPIX7P5GPIOJ0_SGPMCKJ5GPIOJ1_SGPMLDJ4GPIOJ2_SGPMOK5GPIOJ3_SGPMIJ3NTRSTE1TDI_BDMF1TMSG2TCKF2RTCKG4TDOG3GPIOG0_SGPSCKA14GPIOG1_SGPSLDE13GPIOG2_SGPSI0D13GPIOG3_SGPSI1C13GPIOG5_WDTRST2_USBCKIY21GPIOG6_FLBUSY#AA22GPIOG7_FLWP#U18GPIOG4_WDTRST1_OSCCLKB13GPIOA0_MAC1LINKD6GPIOA1_MAC2LINKB5GPIOA2_TIMER3A4GPIOA3_TIMER4E6GPIOB4_LPCRST#E19GPIOB5_LPCPD#_LPCSMI#H19GPIOB6_LPCPME#H20GPIOB7_EXTRST#_SPICS1#E18GPIOP0_TACH8_VPIR6Y6GPIOP1_TACH9_VPIR7AB5GPIOP2_TACH10_VPIR8W7GPIOP3_TACH11_VPIR9AA6GPIOP4_TACH12AB6GPIOP5_TACH13Y7GPIOP6_TACH14_BMCINTAA7GPIOP7_TACH15_FLACKAB7GPION0_PWM0_VPIG0W4GPION1_PWM1_VPIG1Y3GPION2_PWM2_VPIG2AA2GPION3_PWM3_VPIG3AB1GPIOY1_SIOS5#F20GPIOY0_SIOS3#C21GPIOY2_SIOPWREQ#G20
R3180R2J-2-GP12
R3220R2J-2-GP12
 R32410KR2F-2-GP12TP1771
 R54610KR2F-2-GP12
R33510KR2F-2-GP12
R562 0R2J-2-GP12
R3160R2J-2-GP12
R36040R2J-2-GP12
R630 0R2J-2-GP12
 SR8524K75R2F-1-GP12
R80030R2J-2-GP12
R33347KR2F-GP12
R8014K7R2F-GP
NOPOP
12
 U8074AHC1G08DCKR-GPA1B2GND3Y4VCC5
TP3181
R33447KR2F-GP
NOPOP
12
R3190R2J-2-GP12
C187SCD1U16V2KX-3GP12
R3360R2J-2-GP
NOPOP
12
C188SC1U10V3KX-4GP-U
NOPOP
12
R743 0R2J-2-GPNOPOP12
R224 4K7R2F-GP12
SR9434K75R2F-1-GP
NOPOP
12TP2321
TP1791
R220 4K7R2F-GP12TP2301
R30110KR2F-2-GP12
 R3080R2J-2-GP12
R8034K7R2F-GP12TP1811
 C272SCD1U16V2KX-3GP12
TP3201
R223 4K7R2F-GP12
R806 0R2J-2-GP12
 U35SN74LVC1G07DCKRG4-2-GPGND3A2NC#11VCC5Y4
R687 0R2J-2-GPNOPOP12
R3178K2R2J-3-GP12
R523 0R2J-2-GP12
R229 4K7R2F-GP12



5
5
4
4
3
3
2
2
1
1
D D
C C
B B
A A
DACRSETADCAV33ADCVREFFNADCVREFFPADCVREXTV1PLLAV12MPLLAV33V1PLLAV12MPLLAV33ADCAV33P1V26_STBY
P3V3_STBY
P1V26_STBYP1V53_STBYP3V3_STBYP1V53_STBYP1V26_STBYP3V3_STBYP3V3_STBYP1V26_STBYP3V3_STBYP3V3_STBY
Title
Size Document Number R e v
Date: Sheet o f
Lightning PMC PEB -11AST2400 PowerA315 60Friday, March 31, 2017Lightning PMC PEB -1http://www.wiwynn.com8F, 90, Sec.1, Xintai 5th Rd., Xizhi Dist.,New Taipei City 22102, Taiwan (R.O.C.)
Title
Size Document Number R e v
Date: Sheet o f
Lightning PMC PEB -11AST2400 PowerA315 60Friday, March 31, 2017Lightning PMC PEB -1http://www.wiwynn.com8F, 90, Sec.1, Xintai 5th Rd., Xizhi Dist.,New Taipei City 22102, Taiwan (R.O.C.)
Title
Size Document Number R e v
Date: Sheet o f
Lightning PMC PEB -11AST2400 PowerA315 60Friday, March 31, 2017Lightning PMC PEB -1http://www.wiwynn.com8F, 90, Sec.1, Xintai 5th Rd., Xizhi Dist.,New Taipei City 22102, Taiwan (R.O.C.)
C194SC1U10V2KX-4-GP12
 C205SC1U10V2KX-4-GP12
C202SCD1U16V2KX-3GP12
 C200SC1U10V2KX-4-GP12
L4MMZ2012S601ATA1N-GP68.00109.17112
C218SC1U10V2KX-4-GP12
C196SC100P50V2JN-3GP12
C219SC1U10V2KX-4-GP12
 C209SC220P50V2KX-3GP12
C192SC1U10V2KX-4-GP12
 R337 49K9R2F-L-GP12
C210SC1U10V2KX-4-GP12
C213SC1U10V2KX-4-GP12
R3382K74R3F-GP12
C203SC100P50V2JN-3GP12
 C189SCD1U16V2KX-3GP
NOPOP
12
C212SC1U10V2KX-4-GP12
 C211SC220P50V2KX-3GP12
C197SC1U10V2KX-4-GP12
C216SC1U10V2KX-4-GP12
C193SC100P50V2JN-3GP12
C217SC1U10V2KX-4-GP12
C198SC1U10V2KX-4-GP12
C214SC1U10V2KX-4-GP12
L5MMZ2012S601ATA1N-GP68.00109.17112
 C206SC1U10V2KX-4-GP12
C215SC1U10V2KX-4-GP12
C201SC1U10V2KX-4-GP12
C195SCD1U16V2KX-3GP12
 C207SC1U10V2KX-4-GP12
C199SC1U10V2KX-4-GP12
C208SC1U10V2KX-4-GP12
4 OF 4
U40D
AST2400A1-GPGNDJ10GNDJ11GNDJ12GNDJ13GNDJ14GNDJ9GNDK10GNDK11GNDK12GNDK13GNDK14GNDK9GNDL10GNDL11GNDL12GNDL13GNDL14GNDL9GNDM10GNDM11GNDM12GNDM13GNDM14GNDM9GNDN10GNDN11GNDN12GNDN13GNDN14GNDN9GNDP10GNDP11GNDP12GNDP13GNDP14GNDP9R2VDDF8R2VDDF9R1VDDF10R1VDDF11MVDDU10MVDDU11MVDDU14MVDDU15PV33DF12PV33DF13PV33DH6PV33DH17PV33DJ6PEAV33J17PV33DM6PV33DM17PV33DN6PV33DN17PV33DU8PV33DU9
IV12DF14IV12DF15IV12DK6PEAV12K17IV12DL6IV12DL17IV12DP6IV12DP17IV12DR6IV12DR17IV12DU12IV12DU13MPLLAV33AB19HPLLAV33V17MPLLDV12Y18V1PLLAV12W19V2PLLAV12Y20PLLVSSAA19PLLVSSAA18PLLVSSV18DACAV33P1DACAVSSR5DACRSETR1DACDV33T3ADCVREFNK2ADCVREFPK1ADCAVSSP4ADCAV33P3ADCREXTP2NC#H21H21NC#H22H22PEAGNDD21PEAGNDD22
C204SC1U10V2KX-4-GP12
L6MMZ2012S601ATA1N-GP68.00109.17112
 C190SCD1U16V2KX-3GP
NOPOP
12
C191SCD1U16V2KX-3GP
NOPOP
12



5
5
4
4
3
3
2
2
1
1
D D
C C
B B
A A
1-2
2-3(default) BMC enable
BMC disable
ROMD0_RROMD2ROMD3ROMD4ROMD5ROMD1_RROMD6ROMD7ROMA11ROMA12ROMA13ROMA14ROMA15ROMA0ROMA16ROMA17ROMA18ROMA19ROMA20ROMA2ROMA21ROMA22ROMA3ROMA23ROMA4ROMA5ROMA1ROMA6ROMA7ROMA8ROMA9ROMA10AS_ROMA0_RROMA0P3V3_STBYP3V3_STBYP3V3_STBYP3V3_STBYP3V3_STBYROMA[23..0]13 ROMD0_R 13ROMD1_R 13ROMD2 13ROMD3 13ROMD4 13ROMD5 13ROMD6 13ROMD7 13ROMA0 13
Title
Size Document Number R e v
Date: Sheet o f
Lightning PMC PEB -11AST2400 STRAPPINGA316 60Friday, March 31, 2017Lightning PMC PEB -1http://www.wiwynn.com8F, 90, Sec.1, Xintai 5th Rd., Xizhi Dist.,New Taipei City 22102, Taiwan (R.O.C.)
Title
Size Document Number R e v
Date: Sheet o f
Lightning PMC PEB -11AST2400 STRAPPINGA316 60Friday, March 31, 2017Lightning PMC PEB -1http://www.wiwynn.com8F, 90, Sec.1, Xintai 5th Rd., Xizhi Dist.,New Taipei City 22102, Taiwan (R.O.C.)
Title
Size Document Number R e v
Date: Sheet o f
Lightning PMC PEB -11AST2400 STRAPPINGA316 60Friday, March 31, 2017Lightning PMC PEB -1http://www.wiwynn.com8F, 90, Sec.1, Xintai 5th Rd., Xizhi Dist.,New Taipei City 22102, Taiwan (R.O.C.)
R341 3K3R2F-2-GPNOPOP12
R353 3K3R2F-2-GP12
R370 3K3R2F-2-GPNOPOP12
R354 3K3R2F-2-GPNOPOP12
R369 3K3R2F-2-GPNOPOP12
R342 3K3R2F-2-GPNOPOP12
R345 3K3R2F-2-GP12
R347 3K3R2F-2-GPNOPOP12
 R365 3K3R2F-2-GPNOPOP12
R346 3K3R2F-2-GP12
R351 3K3R2F-2-GPNOPOP12
 R362 3K3R2F-2-GPNOPOP12
R344 3K3R2F-2-GPNOPOP12
 R366 3K3R2F-2-GPNOPOP12
R349 3K3R2F-2-GP12
R343 3K3R2F-2-GP12
R348 3K3R2F-2-GP12
 R3393K3R2F-2-GP12
R340 3K3R2F-2-GPNOPOP12
R363 3K3R2F-2-GPNOPOP12
R364 3K3R2F-2-GPNOPOP12
R352 3K3R2F-2-GPNOPOP12
 R350 3K3R2F-2-GPNOPOP12
R359 3K3R2F-2-GPNOPOP12
R360 3K3R2F-2-GPNOPOP12
 JP1PIN-CON3-S-GP123
R356 3K3R2F-2-GPNOPOP12
 R358 3K3R2F-2-GPNOPOP12
R367 3K3R2F-2-GPNOPOP12
R368 3K3R2F-2-GPNOPOP12
R355 3K3R2F-2-GPNOPOP12
 R361 3K3R2F-2-GPNOPOP12
R357 3K3R2F-2-GPNOPOP12



5
5
4
4
3
3
2
2
1
1
D D
C C
B B
A A
ADC Voltage Divider
P0V9_E
P5V_STBY
P12VP1V8_STBYP1V53_STBYP3V3_STBYP0V9P1V26_STBYADC_P0V9_E 14
ADC_P5V_STBY 14
ADC_12V 14ADC_P1V8_STBY 14ADC_P1V53V 14ADC_P3V3_STBY 14ADC_P0V9 14ADC_P1V26 14
Title
Size Document Number Rev
Date: Sheet o f
Lightning PMC PEB -11AST2400_VOLTAGE SENSECustom17 60Friday, March 31, 2017Lightning PMC PEB -1http://www.wiwynn.com8F, 90, Sec.1, Xintai 5th Rd., Xizhi Dist.,New Taipei City 22102, Taiwan (R.O.C.)
Title
Size Document Number Rev
Date: Sheet o f
Lightning PMC PEB -11AST2400_VOLTAGE SENSECustom17 60Friday, March 31, 2017Lightning PMC PEB -1http://www.wiwynn.com8F, 90, Sec.1, Xintai 5th Rd., Xizhi Dist.,New Taipei City 22102, Taiwan (R.O.C.)
Title
Size Document Number Rev
Date: Sheet o f
Lightning PMC PEB -11AST2400_VOLTAGE SENSECustom17 60Friday, March 31, 2017Lightning PMC PEB -1http://www.wiwynn.com8F, 90, Sec.1, Xintai 5th Rd., Xizhi Dist.,New Taipei City 22102, Taiwan (R.O.C.)
R57711KR2F-3-GP12
C8087SCD1U25V2KX-2-GP12
C8084SCD1U25V2KX-2-GP12
R4343K3R2F-2-GP12
C8085SCD1U25V2KX-2-GP12
C8083SCD1U25V2KX-2-GP12
R57661KR2F-3-GP12
R57701KR2F-3-GP12
C8086SCD1U25V2KX-2-GP12
 R57631KR2F-3-GP12
R57651K8R2F-GP12
R30291KR2F-3-GP12
R57671KR2F-3-GP
NOPOP
12
R57691KR2F-3-GP12
R57681KR2F-3-GP12
 C8089SCD1U25V2KX-2-GP12
R30981KR2F-3-GP
NOPOP
12
C8081SCD1U25V2KX-2-GP12
R57645K6R2F-2-GP12
 R57721KR2F-3-GP12
C8088SCD1U25V2KX-2-GP12
 R30991KR2F-3-GP
NOPOP
12
R57621KR2F-3-GP
NOPOP
12
R31001KR2F-3-GP
NOPOP
12



5
5
4
4
3
3
2
2
1
1
D D
C C
B B
A A
Title
Size Document Number R e v
Date: Sheet o f
Lightning PMC PEB -11RESERVEA318 60Friday, March 31, 2017Lightning PMC PEB -1http://www.wiwynn.com8F, 90, Sec.1, Xintai 5th Rd., Xizhi Dist.,New Taipei City 22102, Taiwan (R.O.C.)
Title
Size Document Number R e v
Date: Sheet o f
Lightning PMC PEB -11RESERVEA318 60Friday, March 31, 2017Lightning PMC PEB -1http://www.wiwynn.com8F, 90, Sec.1, Xintai 5th Rd., Xizhi Dist.,New Taipei City 22102, Taiwan (R.O.C.)
Title
Size Document Number R e v
Date: Sheet o f
Lightning PMC PEB -11RESERVEA318 60Friday, March 31, 2017Lightning PMC PEB -1http://www.wiwynn.com8F, 90, Sec.1, Xintai 5th Rd., Xizhi Dist.,New Taipei City 22102, Taiwan (R.O.C.)



5
5
4
4
3
3
2
2
1
1
D D
C C
B B
A A
10M
StatusSpeed
None
Yellow
Green
1000M
Right
LED2
100M
LED1
Active
Link Green
Blink
Left
LED_LAN0_1G_N
LED_LAN0_LINK_N
D5
D3
YELLOW
D1 D2
Green
LED_LAN0_100M_N
LED_LAN0_ACT
D4
Green
P3V3_STBY
P3V3_STBY
D4
VF = 1.8V (normal) and IF= 5mA (normal)
Non-pop these resistors when using I210-AS
Confirm the GND
Confirm the GND
Confirm the GND
NIC0_MDI0_P2_RNIC0_MDI0_N0_RNIC0_MDI0_N1_RNIC0_MDI0_P0_RNIC0_MDI0_P1_RNIC0_MDI0_N3_RNIC0_MDI0_P3_RNIC0_MDI0_N2_RLED_MDI0_ACTLED_MDI0_ACTNIC0_CT_POWERLED_MDI0_100M_1G_NLED_MDI0_100M_N_RLED_MDI0_1G_N_RLED_MDI0_1G_NNIC0_CT_POWERLED_MDI0_LINK_NLED_MDI0_100M_NNIC0_MDI0_P2_RNIC0_MDI0_N1_RNIC0_MDI0_N3_RNIC0_MDI0_N0_RNIC0_MDI0_P3_RNIC0_MDI0_N2_RNIC0_MDI0_P0_RNIC0_MDI0_P1_RP3V3_STBYNIC0_MDI0_P3 19,44NIC0_MDI0_N2 19,44NIC0_MDI0_N3 19,44NIC0_MDI0_P2 19,44NIC0_MDI0_P1 44NIC0_MDI0_N0 44NIC0_MDI0_N1 44NIC0_MDI0_P0 44LED_MDI0_LINK_N44LED_MDI0_1G_N44LED_MDI0_100M_N44 NIC0_MDI0_P319,44NIC0_MDI0_N219,44NIC0_MDI0_N319,44NIC0_MDI0_P219,44MNG_RX_DP 43MNG_RX_DN 43MNG_TX_DN 43MNG_TX_DP 43
Title
Size Document Number R e v
Date: Sheet o f
Lightning PMC PEB -11LAN CONNECTORA319 60Friday, March 31, 2017Lightning PMC PEB -1http://www.wiwynn.com8F, 90, Sec.1, Xintai 5th Rd., Xizhi Dist.,New Taipei City 22102, Taiwan (R.O.C.)
Title
Size Document Number R e v
Date: Sheet o f
Lightning PMC PEB -11LAN CONNECTORA319 60Friday, March 31, 2017Lightning PMC PEB -1http://www.wiwynn.com8F, 90, Sec.1, Xintai 5th Rd., Xizhi Dist.,New Taipei City 22102, Taiwan (R.O.C.)
Title
Size Document Number R e v
Date: Sheet o f
Lightning PMC PEB -11LAN CONNECTORA319 60Friday, March 31, 2017Lightning PMC PEB -1http://www.wiwynn.com8F, 90, Sec.1, Xintai 5th Rd., Xizhi Dist.,New Taipei City 22102, Taiwan (R.O.C.)
R515 0R2J-2-GPNOPOP12
R540 0R2J-2-GPNOPOP12
 C335 SCD1U16V2KX-3GPNOPOP12
R539 0R2J-2-GPNOPOP12
D19PGB1010603MR-GP
NOPOP12
C422SCD1U16V2KX-3GP
NOPOP
12
R611 0R2J-2-GPNOPOP12
R597 0R2J-2-GPNOPOP12
D14PGB1010603MR-GP
NOPOP12
 R512 0R2J-2-GPNOPOP12
R560 0R2J-2-GPNOPOP12
R612 0R2J-2-GPNOPOP12
YELLOW
GREEN
GREEN
RJ1RJ45-LED-12P-10-GP
NOPOP
1234567891011121314D1D2D3D4D5NP1NP2
D15PGB1010603MR-GP
NOPOP12
 R603 0R2J-2-GPNOPOP12
R613 0R2J-2-GPNOPOP12
D12PGB1010603MR-GP
NOPOP12
 R582 0R2J-2-GPNOPOP12
R511150R3J-L-GP
NOPOP
12
D11PGB1010603MR-GP
NOPOP12
D16PGB1010603MR-GP
NOPOP12
C414SCD1U16V2KX-3GP
NOPOP
12
 R594 0R2J-2-GPNOPOP12
C329 SCD1U16V2KX-3GPNOPOP12
D17PGB1010603MR-GP
NOPOP12
C330 SCD1U16V2KX-3GPNOPOP12
R595 0R2J-2-GPNOPOP12
C333 SCD1U16V2KX-3GPNOPOP12
R514150R3J-L-GP
NOPOP
12
C420SCD1U16V2KX-3GP
NOPOP
12
D18PGB1010603MR-GP
NOPOP12
 R596 0R2J-2-GPNOPOP12
C334 SCD1U16V2KX-3GPNOPOP12
C421SCD1U16V2KX-3GP
NOPOP
12



5
5
4
4
3
3
2
2
1
1
D D
C C
B B
A A
USB_P1_F_DN1USB_P1_F_DP1USB_DP_RUSB_OC#P5V_USB_BP1_FUSB_DN_RUSB5V_ENUSB_P1_F_DP1USB_P1_F_DN1P5V_USBAGND_USBP5V_USBP5V_STBYP5V_USBAGND_USBBMC_USB_EN_1 14USB_P2_DP14USB_P2_DN14
Title
Size Document Number R e v
Date: Sheet o f
Lightning PMC PEB -11USB2.0*1A320 60Friday, March 31, 2017Lightning PMC PEB -1http://www.wiwynn.com8F, 90, Sec.1, Xintai 5th Rd., Xizhi Dist.,New Taipei City 22102, Taiwan (R.O.C.)
Title
Size Document Number R e v
Date: Sheet o f
Lightning PMC PEB -11USB2.0*1A320 60Friday, March 31, 2017Lightning PMC PEB -1http://www.wiwynn.com8F, 90, Sec.1, Xintai 5th Rd., Xizhi Dist.,New Taipei City 22102, Taiwan (R.O.C.)
Title
Size Document Number R e v
Date: Sheet o f
Lightning PMC PEB -11USB2.0*1A320 60Friday, March 31, 2017Lightning PMC PEB -1http://www.wiwynn.com8F, 90, Sec.1, Xintai 5th Rd., Xizhi Dist.,New Taipei City 22102, Taiwan (R.O.C.)
C337SC1U10V2KX-4-GP12
R4460R3J-0-U-GP12
R6350R3J-0-U-GP
NOPOP12
C240SCD1U16V2JX-1-GP12
R5450R3J-0-U-GP12
L7BLM21PG300SN-2GP12
 C338SC1U10V2KX-4-GP12
R6490R2J-2-GP12
R410 0R2J-2-GP12
R409 0R2J-2-GP12
F1POLYSW-1D5A8V-4-GP
NOPOP
12
R6860R2J-2-GP12
TC10SC10U16V5KX-1-GP12
TC12SC10U16V5KX-1-GP12
TC15SC22U25V6KX-GP-U12
TC11SC10U16V5KX-1-GP12
 SKT1SKT-USB-250-GP123456
C332SCD1U16V2JX-1-GP12TP1471
TC14SC22U25V6KX-GP-U12
U194TPS2065DBVT-GPOUT1GND2OC#3EN4IN5
L8DLW21HN900SQ2LGP-U
NOPOP
1342
Note:ZZ.09904.07C01U22AZC099-04S-1-GPI/O11GND2I/O23I/O34VDD5I/O46
R46 100KR2F-L1-GP12
 C336SC1U10V2KX-4-GP12
C238SCD1U16V2JX-1-GP12
TC17ST150U6D3VDM-28-GP12



5
5
4
4
3
3
2
2
1
1
D D
C C
B B
A A
I2C BUFFERPMC to BMC
I2C BUFFERfor DPB SSD
I2C BUFFERfor DPB sensors
I2C BUFFERFCB eeprom/led driver/ power monitor/ fan controller
I2C BUFFERfor DPB CLK BUFFER/ SSD
I2C BUFFERPEB
BMC_I2C10_8536_SCLI2C10_BUF_READYBUF_I2C_SCL_2_RBMC_I2C10_8536_SDATWI_SDA0TWI_SCL0BMC_I2C10_8536_SDA_RBMC_I2C10_8536_SCL_RI2C10_BUFF_ENBUF_I2C_SDA_2_RBMC_I2C9_CLKBUF2_SCLI2C9_BUF_READYBUF_I2C9_CLKBUF2_SCL_RBMC_I2C9_CLKBUF2_SDABUF_I2C9_CLKBUF2_SDABUF_I2C9_CLKBUF2_SCLBMC_I2C9_CLKBUF2_SDA_RBMC_I2C9_CLKBUF2_SCL_RI2C9_BUFF_ENBUF_I2C9_CLKBUF2_SDA_RI2C7_BUF_READYI2C7_BUFF_ENBUF_I2C7_B_DBP_SCL_RBUF_I2C7_B_DPB_SDA_RBMC_I2C7_B_DPB_SDA_RBMC_I2C7_B_DBP_SCLBMC_I2C7_B_DPB_SDABUF_I2C7_B_DPB_SDABUF_I2C7_B_DBP_SCLBMC_I2C7_B_DBP_SCL_RI2C6_BUF_READYI2C6_BUFF_ENBUF_I2C6_C_FCB_SCL_RBUF_I2C6_C_FCB_SDA_RBMC_I2C6_C_FCB_SDA_RBMC_I2C6_C_FCB_SCLBMC_I2C6_C_FCB_SDABUF_I2C6_C_FCB_SDABUF_I2C6_C_FCB_SCLBMC_I2C6_C_FCB_SCL_RI2C8_BUF_READYI2C8_BUFF_ENBUF_I2C8_CLKBUF1_SCL_RBUF_I2C8_CLKBUF1_SDA_RBMC_I2C8_CLKBUF1_SDA_RBMC_I2C8_CLKBUF1_SCLBMC_I2C8_CLKBUF1_SDABUF_I2C8_CLKBUF1_SDABUF_I2C8_CLKBUF1_SCLBMC_I2C8_CLKBUF1_SCL_RBMC_I2C5_D_PEB_DEVICE_SCLBMC_I2C5_BUF_READYBMC_I2C5_SCL_RBMC_I2C5_D_PEB_DEVICE_SDABMC_I2C5_D_PEB_SDABMC_I2C5_D_PEB_SCLBUF_I2C5_SDA_RBUF_I2C5_SCL_RI2C5_BUFF_ENBMC_I2C5_SDA_RP3V3_STBYP3V3_STBYP3V3_STBYP3V3_STBYP3V3_STBYP3V3_STBYP3V3_STBYP3V3_STBYP3V3_STBYP3V3_STBYP3V3_STBYP3V3_STBYP3V3_STBYP3V3_STBYP3V3_STBYP3V3_STBYP3V3_STBYP3V3_STBYP3V3_STBYP3V3_STBYP3V3_STBYP3V3_STBYP3V3_STBYP3V3_STBYBMC_I2C10_8536_SCL12BMC_I2C10_8536_SDA 12BMC_I2C9_CLKBUF2_SCL12BUF_I2C9_CLKBUF2_SCL27BMC_I2C9_CLKBUF2_SDA 12BUF_I2C9_CLKBUF2_SDA 27BUF_I2C7_B_DBP_SCL27BMC_I2C7_B_DBP_SCL12BUF_I2C7_B_DPB_SDA 27BMC_I2C7_B_DPB_SDA 12
TWI_SDA0 37TWI_SCL037
BUF_I2C6_C_FCB_SCL27BMC_I2C6_C_FCB_SCL12BUF_I2C6_C_FCB_SDA 27BMC_I2C6_C_FCB_SDA 12BUF_I2C8_CLKBUF1_SCL27BMC_I2C8_CLKBUF1_SCL12,29BUF_I2C8_CLKBUF1_SDA 27BMC_I2C8_CLKBUF1_SDA 12,29BMC_I2C5_D_PEB_SDA 11,23,31,36,46BMC_I2C5_D_PEB_SCL11,23,31,36,46BMC_I2C5_D_PEB_DEVICE_SDA 12,26BMC_I2C5_D_PEB_DEVICE_SCL12,26
Title
Size Document Number R e v
Date: Sheet o f
Lightning PMC PEB -11I2C BUFFERCustom21 60Friday, March 31, 2017Lightning PMC PEB -1http://www.wiwynn.com8F, 90, Sec.1, Xintai 5th Rd., Xizhi Dist.,New Taipei City 22102, Taiwan (R.O.C.)
Title
Size Document Number R e v
Date: Sheet o f
Lightning PMC PEB -11I2C BUFFERCustom21 60Friday, March 31, 2017Lightning PMC PEB -1http://www.wiwynn.com8F, 90, Sec.1, Xintai 5th Rd., Xizhi Dist.,New Taipei City 22102, Taiwan (R.O.C.)
Title
Size Document Number R e v
Date: Sheet o f
Lightning PMC PEB -11I2C BUFFERCustom21 60Friday, March 31, 2017Lightning PMC PEB -1http://www.wiwynn.com8F, 90, Sec.1, Xintai 5th Rd., Xizhi Dist.,New Taipei City 22102, Taiwan (R.O.C.)
R8810R2J-2-GP
NOPOP12
 R5022KR2F-3-GP12
R8984K7R2J-2-GP12
 R88710KR2F-2-GP12
R8732KR2F-3-GP12
R9010R2J-2-GP
NOPOP12
 R966 0R2J-2-GPNOPOP12
R50310KR2F-2-GP12
 C703SC220P50V3JN-GPNOPOP12
R8884K7R2J-2-GP12
C707SCD01U50V2KX-1GP12
 R8670R2J-2-GP12
R8840R2J-2-GP12
 R87410KR2F-2-GP12
C709SC220P50V3JN-GPNOPOP12
C261SC220P50V3JN-GPNOPOP12
U24PCA9511ADP-T-GPENABLE1SCLOUT2SCLIN3GND4READY5SDAIN6SDAOUT7VCC8
 R967 0R2J-2-GPNOPOP12
C247SC220P50V3JN-GPNOPOP12
C701SCD01U50V2KX-1GP12
R8830R2J-2-GP12
 R8680R2J-2-GP12
C691SC220P50V3JN-GPNOPOP12
R4320R2J-2-GP12
C262SC220P50V3JN-GPNOPOP12
R8790R2J-2-GP12
R4430R2J-2-GP12
R9020R2J-2-GP
NOPOP12
C692SC220P50V3JN-GPNOPOP12
R8690R2J-2-GP
NOPOP12
R8910R2J-2-GP
NOPOP12
C245SC220P50V3JN-GPNOPOP12
U30PCA9511ADP-T-GPENABLE1SCLOUT2SCLIN3GND4READY5SDAIN6SDAOUT7VCC8
C265SCD01U50V2KX-1GP12
R8610R2J-2-GP
NOPOP12
 C698SC220P50V3JN-GPNOPOP12
R4480R2J-2-GP12
C246SC220P50V3JN-GPNOPOP12
C693SCD01U50V2KX-1GP12
R8700R2J-2-GP
NOPOP12
R8920R2J-2-GP
NOPOP12
R9030R2J-2-GP12
R8800R2J-2-GP12
R8620R2J-2-GP
NOPOP12
 C694SCD1U16V2KX-3GP12
R4310R2J-2-GP12
 R4682KR2F-3-GP12
R9040R2J-2-GP12
 R8712KR2F-3-GP12
R87510KR2F-2-GP12
C699SC220P50V3JN-GPNOPOP12
R4272KR2F-3-GP12
R8930R2J-2-GP12
C253SCD1U16V2KX-3GP12
C244SCD01U50V2KX-1GP12
C696SC220P50V3JN-GPNOPOP12
C688SCD1U16V2KX-3GP12
R8764K7R2J-2-GP12
 R8940R2J-2-GP12
U33PCA9511ADP-T-GPENABLE1SCLOUT2SCLIN3GND4READY5SDAIN6SDAOUT7VCC8
C258SC220P50V3JN-GPNOPOP12
R4292KR2F-3-GP12
R8990R2J-2-GP12
C710SC220P50V3JN-GPNOPOP12
C689SC220P50V3JN-GPNOPOP12
R87710KR2F-2-GP12
C706SCD1U16V2KX-3GP12
 R8890R2J-2-GP12
R43010KR2F-2-GP12
U31PCA9511ADP-T-GPENABLE1SCLOUT2SCLIN3GND4READY5SDAIN6SDAOUT7VCC8
R48610KR2F-2-GP12
C697SC220P50V3JN-GPNOPOP12
R42810KR2F-2-GP12
 R87210KR2F-2-GP12
R8784K7R2J-2-GP12
R89510KR2F-2-GP12
C704SC220P50V3JN-GPNOPOP12
C708SC220P50V3JN-GPNOPOP12
C700SCD1U16V2KX-3GP12
C711SC220P50V3JN-GPNOPOP12
C243SCD1U16V2KX-3GP12
R8630R2J-2-GP
NOPOP12
R8900R2J-2-GP12
R8974K7R2J-2-GP12
C695SCD01U50V2KX-1GP12
U34PCA9511ADP-T-GPENABLE1SCLOUT2SCLIN3GND4READY5SDAIN6SDAOUT7VCC8
C248SC220P50V3JN-GPNOPOP12
R88510KR2F-2-GP12
R9000R2J-2-GP12
 R964 0R2J-2-GPNOPOP12
U29PCA9511ADP-T-GPENABLE1SCLOUT2SCLIN3GND4READY5SDAIN6SDAOUT7VCC8
R8640R2J-2-GP
NOPOP12
 C705SC220P50V3JN-GPNOPOP12
R8650R2J-2-GP12
R8820R2J-2-GP
NOPOP12
R89610KR2F-2-GP12
C259SC220P50V3JN-GPNOPOP12
 R8864K7R2J-2-GP12
C702SC220P50V3JN-GPNOPOP12
C690SC220P50V3JN-GPNOPOP12
R965 0R2J-2-GPNOPOP12
R8660R2J-2-GP12



5
5
4
4
3
3
2
2
1
1
D D
C C
B B
A A
AND GATE
ENCLOSURE STATUS LED - R
Power identify - B
UPLINK indicator - G
Virtual SW Zoning indicator - G
SW zoning:MODE        [LED18]   [LED19]   [LED20]  [LED21]  [LED22]  [LED23]     1X16        ON          OFF       OFF       OFF     OFF      OFF  2X8         OFF         ON        OFF       OFF     OFF      OFF             4X4         OFF         OFF       ON        OFF     OFF      OFF 2X16        OFF         OFF       OFF       ON      OFF      OFF  4X8         OFF         OFF       OFF       OFF     ON       OFF             8X4         OFF         OFF       OFF       OFF     OFF      ON 
Uplink Indication:MODE       [LED8]   [LED9]     [LED10]    [LED11]   X16         ON        OFF        OFF       OFFX8          ON        ON         OFF       OFF        X4          ON        ON         ON        ON 
MODE       [LED12]   [LED13]   [LED15]   [LED16]   X16         ON        OFF        OFF       OFFX8          ON        ON         OFF       OFF        X4          ON        ON         ON        ON 
LED_PWR_N_RENCLO_LED_RED_GBMC_ENCLOSURE_LED_RHB_OUT_RLED_PWR_N_ON
ENCLO_LED_RED_RLED_R_1LED_Q_1UPLINK1_RUPLINK2_RLED_R_2LED_Q_2UPLINK3_RLED_R_3LED_Q_3UPLINK4_RLED_R_4LED_Q_4UPLINK7_RLED_R_7LED_Q_7LED_R_8LED_Q_8UPLINK5_RLED_R_5LED_Q_5UPLINK6_RLED_R_6LED_Q_6VS3_LED_RLED_R_11LED_Q_11VS4_LED_RLED_R_12LED_Q_12VS1_LED_RLED_R_9LED_Q_9VS2_LED_RLED_R_10LED_Q_10UPLINK8_RVS5_LED_RLED_R_13LED_Q_13VS6_LED_RLED_R_14LED_Q_14BMC_ID_LED_RENCLO_LED_RED_DENCLO_LED_REDENCLO_LED_BLUE_OUTP3V3_STBYP5V_STBYP3V3_STBYP5V_STBYP3V3_STBYP3V3_STBYP3V3_STBYP3V3_STBYP3V3_STBYP3V3_STBYP3V3_STBYP3V3_STBYP3V3_STBYP3V3_STBYP3V3_STBYP3V3_STBYP3V3_STBYP3V3_STBY
HB_OUT24,27,32
BMC_ID_LED13
BMC_ENCLOSURE_LED14 UPLINK137UPLINK237UPLINK337UPLINK437UPLINK737UPLINK837UPLINK537UPLINK637VS3_LED37VS4_LED37VS1_LED37VS2_LED37VS5_LED37VS6_LED37LED_DR_LED114
Title
Size Document Number R ev
Date: Sheet o f
Lightning PMC PEB -11LEDCustom22 60Friday, March 31, 2017Lightning PMC PEB -1http://www.wiwynn.com8F, 90, Sec.1, Xintai 5th Rd., Xizhi Dist.,New Taipei City 22102, Taiwan (R.O.C.)
Title
Size Document Number R ev
Date: Sheet o f
Lightning PMC PEB -11LEDCustom22 60Friday, March 31, 2017Lightning PMC PEB -1http://www.wiwynn.com8F, 90, Sec.1, Xintai 5th Rd., Xizhi Dist.,New Taipei City 22102, Taiwan (R.O.C.)
Title
Size Document Number R ev
Date: Sheet o f
Lightning PMC PEB -11LEDCustom22 60Friday, March 31, 2017Lightning PMC PEB -1http://www.wiwynn.com8F, 90, Sec.1, Xintai 5th Rd., Xizhi Dist.,New Taipei City 22102, Taiwan (R.O.C.)
R3260R2J-2-GP12
Q6 2N7002K-1-GPGDS
 Q26 2N7002K-1-GPGDS
SR719150R2F-1-GP12
 LED9LED-YG-51-GPAK
SR713150R2F-1-GP12
Q38 2N7002K-1-GPGDS
Q24 2N7002K-1-GPGDS
R5580R2J-2-GP12
LED12LED-YG-51-GPAK
Q27 2N7002K-1-GPGDS
R5774330R1210J-GP12
Q39 2N7002K-1-GPGDS
SR717150R2F-1-GP12
LED5LED-B-77-GP-U3AK
 LED11LED-YG-51-GPAK
R6220R2J-2-GP12
LED15LED-YG-51-GPAK
LED18LED-YG-51-GPAK
Q30 2N7002K-1-GPGDS
R6080R2J-2-GP12
SR722150R2F-1-GP12
U38SN74LVC1G08DCKR-GPB2A1GND3Y4VCC5
C269SCD1U16V2KX-3GP12
LED20LED-YG-51-GPAK
SR709150R2F-1-GP12
Q31 2N7002K-1-GPGDS
R6250R2J-2-GP12
SR714150R2F-1-GP12
R543330R1210J-GP12
R78920R2J-2-GP12
 Q28 2N7002K-1-GPGDS
SR712150R2F-1-GP12
R6090R2J-2-GP12
SR718150R2F-1-GP12
 R6230R2J-2-GP12
Q29 2N7002K-1-GPGDS
SR716150R2F-1-GP12
LED8LED-YG-51-GPAK
R5441KR2F-3-GP12
SR711150R2F-1-GP12
LED13LED-YG-51-GPAK
LED23LED-YG-51-GPAK
LED4LED-R-126-GP-U21A2K
Q132N7002K-1-GPGDS
Q34 2N7002K-1-GPGDS
R5321KR2F-3-GP12
 R6190R2J-2-GP12
LED10LED-YG-51-GPAK
LED19LED-YG-51-GPAK
R6830R2J-2-GP12
LED16LED-YG-51-GPAK
Q35 2N7002K-1-GPGDS
Q92N7002K-1-GPGDS
R78890R2J-2-GP
NOPOP12
 R6260R2J-2-GP12
LED21LED-YG-51-GPAK
R6430R2J-2-GP12
R6270R2J-2-GP12
SR723150R2F-1-GP12
Q32 2N7002K-1-GPGDS
R3050R2J-2-GP12
 SR708150R2F-1-GP12
R6240R2J-2-GP12
R4240R2J-2-GP12
R6210R2J-2-GP12
SR715150R2F-1-GP12
Q25 2N7002K-1-GPGDS
Q33 2N7002K-1-GPGDS
SR710150R2F-1-GP12
R5291KR2F-3-GP
NOPOP
12
LED22LED-YG-51-GPAK



5
5
4
4
3
3
2
2
1
1
D D
C C
B B
A A
ADD=10100010 (0xA2)
RTC P3V0_BAT_RP3V3_RTCRTC_I2C_SCLRTC_I2C_SDARTC_CLK_OUTRTC_OSCIRTC_OSCORTC_INT_NP3V0_BATP3V3_STBYP3V3_RTCBMC_I2C5_D_PEB_SDA 11,21,31,36,46BMC_I2C5_D_PEB_SCL 11,21,31,36,46
Title
Size Document Number R e v
Date: Sheet o f
Lightning PMC PEB -11RTCA323 60Friday, March 31, 2017Lightning PMC PEB -1http://www.wiwynn.com8F, 90, Sec.1, Xintai 5th Rd., Xizhi Dist.,New Taipei City 22102, Taiwan (R.O.C.)
Title
Size Document Number R e v
Date: Sheet o f
Lightning PMC PEB -11RTCA323 60Friday, March 31, 2017Lightning PMC PEB -1http://www.wiwynn.com8F, 90, Sec.1, Xintai 5th Rd., Xizhi Dist.,New Taipei City 22102, Taiwan (R.O.C.)
Title
Size Document Number R e v
Date: Sheet o f
Lightning PMC PEB -11RTCA323 60Friday, March 31, 2017Lightning PMC PEB -1http://www.wiwynn.com8F, 90, Sec.1, Xintai 5th Rd., Xizhi Dist.,New Taipei City 22102, Taiwan (R.O.C.)
R52021KR2J-1-GP12
R5201 0R2J-2-GP12
U43PCF8563T-1-GPOSCI1OSCO2INT#3VSS4SDA5SCL6CLKOUT7VDD8
C1698SC22UF16V6KX-GP12TP8001
R6554K7R2F-GP12
C307SC15P50V2JN-2-GP
NOPOP
12
C306SC3D9P50V2CN-1GP12
 D13BAT54C-7-F-3-GP123
R184810MR3F-GPNOPOP12
X2XTAL-32D768KHZ-137-GP12
 R5200 0R2J-2-GP12
BAT1AAA-BAT-043-K03-GP123



5
5
4
4
3
3
2
2
1
1
D D
C C
B B
A A
2.8V
0.5V
Heart Beat Circuitry
Switch heart beat LED：blinking：switch  alive
BMC heart beat LED：blinking：BMC  alive
DIVIDER_1_INDIVIDER_2_INHB_A_ININVERTER_G2INVERTER_G1HB_A_OUTEXP_BMC_HB_LED_RQ21_GEXP_BMC_HB_LED_DQ22_GSLED29_AQ22_DP3V3_STBYP3V3_STBYP3V3_STBYP3V3_STBYP3V3_STBYP3V3_STBYP3V3_STBYP3V3_STBYPM8536_HB37HB_OUT 22,27,32HB_OUT_BMC14,24HB_OUT_BMC14,24
Title
Size Document Number R e v
Date: Sheet o f
Lightning PMC PEB -11HEARTBEAT CIRCUITRYCustom24 60Friday, March 31, 2017Lightning PMC PEB -1http://www.wiwynn.com8F, 90, Sec.1, Xintai 5th Rd., Xizhi Dist.,New Taipei City 22102, Taiwan (R.O.C.)
Title
Size Document Number R e v
Date: Sheet o f
Lightning PMC PEB -11HEARTBEAT CIRCUITRYCustom24 60Friday, March 31, 2017Lightning PMC PEB -1http://www.wiwynn.com8F, 90, Sec.1, Xintai 5th Rd., Xizhi Dist.,New Taipei City 22102, Taiwan (R.O.C.)
Title
Size Document Number R e v
Date: Sheet o f
Lightning PMC PEB -11HEARTBEAT CIRCUITRYCustom24 60Friday, March 31, 2017Lightning PMC PEB -1http://www.wiwynn.com8F, 90, Sec.1, Xintai 5th Rd., Xizhi Dist.,New Taipei City 22102, Taiwan (R.O.C.)
SC1310SC10U6D3V5KX-4GPNOPOP12
 R4960R2J-2-GP12
+
-
U41BLM393ADR-1-GP56784
+
-
U41ALM393ADR-1-GP32184
 SR707150R2F-1-GP12
C263SCD1U16V2KX-3GP12
 R47951R2010F-GP12
R4851KR2F-3-GP12
R4774K7R2F-GP12
R4782MR2F-GP12
R4940R2J-2-GP12
 Q212N7002K-1-GPGDS
R4820R2J-2-GP12
Q102N7002DW-7F-GP123456
 SR720150R2F-1-GP12
R481200R3F-GP12
R4841KR2F-3-GP12
C304SC1U10V2KX-4-GP12
SLED29LED-YG-51-GPAK
R4830R2J-2-GP
NOPOP12
R48010KR2F-2-GP12
Q222N7002K-1-GPGDS
 SLED28LED-YG-51-GPAK



5
5
4
4
3
3
2
2
1
1
D D
C C
B B
A A
Debug Port 
BMC_UART_SWITCH
0     0
1     1
UARTIN1 IN2
PM8536
BMC
YELLOW LED
Remove CN8 header
UART ：BMC  or  PM8536   indecated  LEDLED:on  -> PM8536LED:off -> BMC
Default : Switch to BMC
DEBUG_CARD_TXDEBUG_CARD_RXDEBUG_CARD_TXUART_COUNTDEBUG_CARD_RXEXP_UART_TX_REXP_UART_RX_R
UART_COUNTDP_RST_NBMC_CONSOLE_LED0_RBMC_UART_SWITCH_1CONSOLE_LED_0DEBUG_CONSOLE_LED_0UART_SWITCH_RUART_SWITCH_RP3V3_STBY
P5V_STBYP3V3_STBYP3V3_STBY
P3V3_STBYP3V3_STBYDP_RST_N14,32LOW_HEX_1 14LOW_HEX_014LOW_HEX_3 14LOW_HEX_214HIGH_HEX_014HIGH_HEX_1 14HIGH_HEX_214HIGH_HEX_3 14BMC_UART_SWITCH_114
UART_COUNT 14
BMC_TXD5 13BMC_RXD5 13EXP_SMART_TX 13,37EXP_SMART_RX 13,37
Title
Size Document Number R e v
Date: Sheet o f
Lightning PMC PEB -11DEBUG PORTA325 60Friday, March 31, 2017Lightning PMC PEB -1http://www.wiwynn.com8F, 90, Sec.1, Xintai 5th Rd., Xizhi Dist.,New Taipei City 22102, Taiwan (R.O.C.)
Title
Size Document Number R e v
Date: Sheet o f
Lightning PMC PEB -11DEBUG PORTA325 60Friday, March 31, 2017Lightning PMC PEB -1http://www.wiwynn.com8F, 90, Sec.1, Xintai 5th Rd., Xizhi Dist.,New Taipei City 22102, Taiwan (R.O.C.)
Title
Size Document Number R e v
Date: Sheet o f
Lightning PMC PEB -11DEBUG PORTA325 60Friday, March 31, 2017Lightning PMC PEB -1http://www.wiwynn.com8F, 90, Sec.1, Xintai 5th Rd., Xizhi Dist.,New Taipei City 22102, Taiwan (R.O.C.)
R412 0R2J-2-GP12
 R85150R2F-1-GP12
CN3JWT-CONN14A-1-GP1357946810211121314
R1734K7R2F-GP12
R1764K7R2F-GP
NOPOP
12
 R1744K7R2F-GP12
LED14LED-Y-11-GP12
R4540R2J-2-GP12
C4SCD1U16V2KX-3GP12
R435 0R2J-2-GP12
R2750R2J-2-GP12
R1754K7R2F-GP
NOPOP
12
 C319SCD1U16V2KX-3GP12
C322SCD1U16V2KX-3GP
NOPOP
12
U27TS5A23157DGSR-GPIN11NO12GND3NO24IN25COM26NC27V+8NC19COM110
Q192N7002K-1-GPGDS
C249SCD1U16V2KX-3GP12



5
5
4
4
3
3
2
2
1
1
D D
C C
B B
A A
L : TPM insertH : TPM not insert
FM_TPM_PRES_RST_NVREF_2V2FM_TPM_PRES_RST_N_RBMC_TPM_RSTFM_TPM_PRES_RST
FM_TPM_PRES_RST_NI2C_TPM_SCLI2C_TPM_SDA
FM_TPM_PRES_RST_N_CQ20_GP3V3_STBYP3V3_STBYP3V3_STBYP3V3_STBYP5V_STBYP3V3_STBY
P3V3_STBYP3V3_STBYRST_BMC_EXTRST_N 14FM_TPM_PRES_N 14BMC_I2C5_D_PEB_DEVICE_SDA 12,21BMC_I2C5_D_PEB_DEVICE_SCL12,21
FM_BMC_RESET_N13,14,44BMC_SELF_HW_RST14
Title
Size Document Number R e v
Date: Sheet o f
Lightning PMC PEB -11TPM CONNA326 60Friday, March 31, 2017Lightning PMC PEB -1http://www.wiwynn.com8F, 90, Sec.1, Xintai 5th Rd., Xizhi Dist.,New Taipei City 22102, Taiwan (R.O.C.)
Title
Size Document Number R e v
Date: Sheet o f
Lightning PMC PEB -11TPM CONNA326 60Friday, March 31, 2017Lightning PMC PEB -1http://www.wiwynn.com8F, 90, Sec.1, Xintai 5th Rd., Xizhi Dist.,New Taipei City 22102, Taiwan (R.O.C.)
Title
Size Document Number R e v
Date: Sheet o f
Lightning PMC PEB -11TPM CONNA326 60Friday, March 31, 2017Lightning PMC PEB -1http://www.wiwynn.com8F, 90, Sec.1, Xintai 5th Rd., Xizhi Dist.,New Taipei City 22102, Taiwan (R.O.C.)
C276SCD1U16V2KX-3GP12
 R294710KR2F-2-GP12
R294310KR2F-2-GP12
R4950R2J-2-GP12
 R29444K75R2F-1-GP12
C41SC1U16V3KX-5GP12
U42SN74LVC1G07DCKRG4-2-GPGND3A2NC#11VCC5Y4
C285SC2D2U16V3KX-GP-U12
R2939470KR2F-1-GP12
D1404BAT54WS-7-F-GPAK
 R29490R2J-2-GP12
Q202N7002-7F-GPGSD
Q41TMBT3904-GPCBE
R29480R2J-2-GP12
C155SCD1U16V2JX-1-GP12
R294247KR2F-GP12
R29504K75R2F-1-GP12
 C43SCD1U16V2KX-L-GP12
R29454K75R2F-1-GP12
PAD5STF256R168H278-GP1
CN11FCI-CONN11-2-GP1234567891011G1G2NP1NP2
R294610KR2F-2-GP12
Q36TMBT3904-GPCBE
+
-
U204LMV331IDCKRG4-GP13452
R294110KR2F-2-GP
NOPOP
12
R2938 0R2J-2-GPNOPOP12
R2940100KR2F-L1-GP12



5
5
4
4
3
3
2
2
1
1
D D
C C
B B
A A
stack2
stack1
stack2
stack1
stack2stack1
stack3stack2
stack4stack3
stack3
stack2stack3
stack2
stack4
stack3
stack3
stack4
Note:Pin swap to optimize PDPB routing.
P12V_PCIEP12V_PCIE
SSD_PWREN1_R41SSD_PWREN10_R 41SSD_PWREN5_R 41SSD_PWREN0_R41SSD_PWREN3_R41SSD_PWREN12_R 41SSD_PWREN7_R 41SSD_PWREN2_R41SSD_PWREN11_R 41SSD_PWREN6_R41
SSD_PWREN14_R 41SSD_PWREN9_R41SSD_PWREN13_R41SSD_PWREN4_R 41SSD_PWREN8_R 41SSD_PRSNT#4_R 41SSD_PRSNT#9_R41SSD_PRSNT#14_R41SSD_PRSNT#1_R41SSD_PRSNT#10_R 41SSD_PRSNT#5_R 41SSD_PRSNT#0_R41SSD_PRSNT#3_R41SSD_PRSNT#12_R 41SSD_PRSNT#7_R41SSD_PRSNT#2_R41SSD_PRSNT#11_R 41SSD_PRSNT#6_R41SSD_PRSNT#13_R41SSD_PRSNT#8_R 41SSD_ATNLED#10_R 41SSD_ATNLED#1_R41SSD_ATNLED#5_R 41SSD_ATNLED#0_R41SSD_ATNLED#3_R41SSD_ATNLED#12_R 41SSD_ATNLED#7_R41SSD_ATNLED#2_R41SSD_ATNLED#11_R 41SSD_ATNLED#6_R41
SSD_ATNLED#14_R 41SSD_ATNLED#9_R41SSD_ATNLED#4_R 41SSD_ATNLED#13_R41PCIE_REFCLK_S1_P36PCIE_REFCLK_S1_N36PCIE_REFCLK_S2_N 36PCIE_REFCLK_S2_P 36
SSD_PERST#8_R 32,41SSD_PERST#9_R32,41SSD_PERST#13_R32,41SSD_PERST#1_R32,41SSD_PERST#0_R32,41PCIE_REFCLK_S3_N 36PCIE_REFCLK_S3_P 36FCB_HW_REVISION 14DPB_HW_REVISION 14PCIE_REFCLK_S4_N36PCIE_REFCLK_S4_P36PEER_BMC_HB 14HB_OUT 22,24,32BMC_SELF_TRAY 14PEER_TRAY_R 14
SSD_PERST#10_R 32,41
SSD_PERST#6_R 32,41SSD_PERST#7_R 32,41SSD_PERST#2_R 32,41SSD_PERST#11_R 32,41SSD_PERST#12_R 32,41SSD_PERST#3_R32,41SSD_PERST#4_R 32,41SSD_PERST#5_R 32,41I2C_MUX_RESET_PEB 12PCIe_MATED#_B46PCIe_MATED#_A46PWM_EXP_A14 SHUTDOWN_RELEASE32BUF_I2C9_CLKBUF2_SDA21BUF_I2C9_CLKBUF2_SCL21BUF_I2C7_B_DPB_SDA21BUF_I2C7_B_DBP_SCL21BUF_I2C6_C_FCB_SDA21BUF_I2C6_C_FCB_SCL21BUF_I2C8_CLKBUF1_SDA 21BUF_I2C8_CLKBUF1_SCL 21
PCIE_TX_P1833PCIE_TX_N1833PCIE_TX_N1933PCIE_TX_P1933PCIE_TX_P1633PCIE_TX_N1633PCIE_TX_N1733PCIE_TX_P1733PCIE_RX_N16 33PCIE_RX_P16 33PCIE_RX_N17 33PCIE_RX_P17 33PCIE_RX_P18 33PCIE_RX_N18 33PCIE_RX_P19 33PCIE_RX_N19 33PCIE_TX_P2033PCIE_TX_N2033PCIE_TX_N2133PCIE_TX_P2133PCIE_TX_P2233PCIE_TX_N2233PCIE_TX_N2333PCIE_TX_P2333PCIE_RX_P20 33PCIE_RX_N20 33PCIE_RX_N21 33PCIE_RX_P21 33PCIE_RX_P22 33PCIE_RX_N22 33PCIE_RX_N23 33PCIE_RX_P23 33PCIE_TX_N2433PCIE_TX_P2433PCIE_TX_P2533PCIE_TX_N2533PCIE_RX_P24 33PCIE_RX_N24 33PCIE_RX_N25 33PCIE_RX_P25 33PCIE_TX_N2633PCIE_TX_P2633PCIE_TX_P2733PCIE_TX_N2733PCIE_RX_N26 33PCIE_RX_P26 33PCIE_RX_N27 33PCIE_RX_P27 33PCIE_TX_P2833PCIE_TX_N2833PCIE_TX_N2933PCIE_TX_P2933PCIE_TX_P3033PCIE_TX_N3033PCIE_TX_P3133PCIE_TX_N3133PCIE_RX_P28 33PCIE_RX_N28 33PCIE_RX_N29 33PCIE_RX_P29 33PCIE_RX_P30 33PCIE_RX_N30 33PCIE_RX_N31 33PCIE_RX_P31 33PCIE_TX_N3234PCIE_TX_P3234PCIE_TX_N3334PCIE_TX_P3334PCIE_TX_P3434PCIE_TX_N3434PCIE_TX_N3534PCIE_TX_P3534PCIE_TX_P3634PCIE_TX_N3634PCIE_TX_P3734PCIE_TX_N3734PCIE_RX_P34 34PCIE_RX_N34 34PCIE_RX_N35 34PCIE_RX_P35 34PCIE_RX_N32 34PCIE_RX_P32 34PCIE_RX_N33 34PCIE_RX_P33 34PCIE_RX_N36 34PCIE_RX_P36 34PCIE_RX_N37 34PCIE_RX_P37 34
PCIE_TX_P3834PCIE_TX_N3834PCIE_TX_P3934PCIE_TX_N3934PCIE_RX_N38 34PCIE_RX_P38 34PCIE_RX_P39 34PCIE_RX_N39 34PCIE_TX_P4634PCIE_TX_N4634PCIE_TX_P4734PCIE_TX_N4734PCIE_TX_P4034PCIE_TX_N4034PCIE_TX_N4134PCIE_TX_P4134PCIE_TX_N4234PCIE_TX_P4234PCIE_TX_N4334PCIE_TX_P4334PCIE_TX_N4434PCIE_TX_P4434PCIE_TX_P4534PCIE_TX_N4534PCIE_RX_P40 34PCIE_RX_N40 34PCIE_RX_N46 34PCIE_RX_P46 34PCIE_RX_P41 34PCIE_RX_N41 34PCIE_RX_P42 34PCIE_RX_N42 34PCIE_RX_N43 34PCIE_RX_P43 34PCIE_RX_N44 34PCIE_RX_P44 34PCIE_RX_N45 34PCIE_RX_P45 34PCIE_RX_P47 34PCIE_RX_N47 34PCIE_TX_P4834PCIE_TX_N4834PCIE_TX_P4934PCIE_TX_N4934PCIE_TX_P5034PCIE_TX_N5034PCIE_TX_P5134PCIE_TX_N5134PCIE_RX_P48 34PCIE_RX_N48 34PCIE_RX_N49 34PCIE_RX_P49 34PCIE_RX_N50 34PCIE_RX_P50 34PCIE_RX_N51 34PCIE_RX_P51 34PCIE_TX_P5234PCIE_TX_N5234PCIE_TX_P5334PCIE_TX_N5334PCIE_RX_N52 34PCIE_RX_P52 34PCIE_RX_N53 34PCIE_RX_P53 34PCIE_TX_N5434PCIE_TX_P5434PCIE_TX_N5534PCIE_TX_P5534PCIE_TX_N5634PCIE_TX_P5634PCIE_TX_N5734PCIE_TX_P5734PCIE_TX_P5834PCIE_TX_N5834PCIE_TX_P5934PCIE_TX_N5934PCIE_RX_N54 34PCIE_RX_P54 34PCIE_RX_N55 34PCIE_RX_P55 34PCIE_RX_P56 34PCIE_RX_N56 34PCIE_RX_P57 34PCIE_RX_N57 34PCIE_RX_P58 34PCIE_RX_N58 34PCIE_RX_P59 34PCIE_RX_N59 34
PCIE_TX_P6034PCIE_TX_N6034PCIE_TX_P6134PCIE_TX_N6134PCIE_TX_P6234PCIE_TX_N6234PCIE_TX_P6334PCIE_TX_N6334PCIE_RX_P60 34PCIE_RX_N60 34PCIE_RX_P61 34PCIE_RX_N61 34PCIE_RX_P62 34PCIE_RX_N62 34PCIE_RX_P63 34PCIE_RX_N63 34PCIE_TX_P6535PCIE_TX_N6435PCIE_TX_P6435PCIE_TX_N6535PCIE_TX_P6735PCIE_TX_N6635PCIE_TX_P6635PCIE_TX_P6835PCIE_TX_N6835PCIE_TX_N6735PCIE_RX_N64 35PCIE_RX_P64 35PCIE_RX_P65 35PCIE_RX_N65 35PCIE_RX_N66 35PCIE_RX_P66 35PCIE_RX_P67 35PCIE_RX_N67 35PCIE_RX_N68 35PCIE_RX_P68 35PCIE_TX_N7035PCIE_TX_P6935PCIE_TX_N6935PCIE_TX_P7135PCIE_TX_N7135PCIE_TX_P7035PCIE_RX_P69 35PCIE_RX_N69 35PCIE_RX_P70 35PCIE_RX_N70 35PCIE_RX_P71 35PCIE_RX_N71 35PCIE_TX_N7335PCIE_TX_P7235PCIE_TX_N7235PCIE_TX_N7535PCIE_TX_N7435PCIE_TX_P7435PCIE_TX_P7335PCIE_TX_P7535PCIE_RX_P74 35PCIE_RX_N74 35PCIE_RX_P75 35PCIE_RX_N75 35PCIE_RX_N72 35PCIE_RX_P72 35PCIE_RX_P73 35PCIE_RX_N73 35SSD_ATNLED#8_R 41SSD_PERST#14_R 32,41EXP_TRAY_ID14
Title
Size Document Number R e v
Date: Sheet o f
Lightning PMC PEB -11200 PIN G/FCustom27 60Friday, March 31, 2017Lightning PMC PEB -1http://www.wiwynn.com8F, 90, Sec.1, Xintai 5th Rd., Xizhi Dist.,New Taipei City 22102, Taiwan (R.O.C.)
Title
Size Document Number R e v
Date: Sheet o f
Lightning PMC PEB -11200 PIN G/FCustom27 60Friday, March 31, 2017Lightning PMC PEB -1http://www.wiwynn.com8F, 90, Sec.1, Xintai 5th Rd., Xizhi Dist.,New Taipei City 22102, Taiwan (R.O.C.)
Title
Size Document Number R e v
Date: Sheet o f
Lightning PMC PEB -11200 PIN G/FCustom27 60Friday, March 31, 2017Lightning PMC PEB -1http://www.wiwynn.com8F, 90, Sec.1, Xintai 5th Rd., Xizhi Dist.,New Taipei City 22102, Taiwan (R.O.C.)
TOP BOTTOM
02 Do not mirror
GF8
GF-200P-8-GP-U1
G#A1A1S#A2A2S#A3A3G#A4A4S#A5A5S#A6A6G#A7A7S#A8A8S#A9A9G#A10A10S#A11A11S#A12A12G#A13A13S#A14A14S#A15A15G#A16A16S#A17A17S#A18A18G#A19A19S#A20A20S#A21A21G#A22A22S#A23A23S#A24A24G#A25A25S#A26A26S#A27A27G#A28A28S#A29A29S#A30A30G#A31A31S#A32A32S#A33A33G#A34A34S#A35A35S#A36A36G#A37A37S#A38A38S#A39A39G#A40A40S#A41A41S#A42A42G#A43A43R#A44A44G#A45A45S#A46A46S#A47A47G#A48A48S#A49A49S#A50A50G#A51A51S#A52A52S#A53A53G#A54A54S#A55A55S#A56A56G#A57A57S#A58A58S#A59A59G#A60A60S#A61A61S#A62A62G#A63A63S#A64A64S#A65A65G#A66A66S#A67A67S#A68A68G#A69A69S#A70A70S#A71A71G#A72A72S#A73A73S#A74A74G#A75A75S#A76A76S#A77A77G#A78A78S#A79A79S#A80A80G#A81A81S#A82A82S#A83A83G#A84A84S#A85A85S#A86A86G#A87A87S#A88A88S#A89A89G#A90A90S#A91A91S#A92A92G#A93A93S#A94A94S#A95A95G#A96A96S#A97A97S#A98A98G#A99A99R#A100A100
R#B1B1G#B2B2S#B3B3S#B4B4G#B5B5S#B6B6S#B7B7G#B8B8S#B9B9S#B10B10G#B11B11S#B12B12S#B13B13G#B14B14S#B15B15S#B16B16G#B17B17S#B18B18S#B19B19G#B20B20S#B21B21S#B22B22G#B23B23S#B24B24S#B25B25G#B26B26S#B27B27S#B28B28G#B29B29S#B30B30S#B31B31G#B32B32S#B33B33S#B34B34G#B35B35S#B36B36S#B37B37G#B38B38S#B39B39S#B40B40G#B41B41S#B42B42S#B43B43G#B44B44R#B45B45G#B46B46S#B47B47S#B48B48G#B49B49S#B50B50S#B51B51G#B52B52S#B53B53S#B54B54G#B55B55S#B56B56S#B57B57G#B58B58S#B59B59S#B60B60G#B61B61S#B62B62S#B63B63G#B64B64S#B65B65S#B66B66G#B67B67S#B68B68S#B69B69G#B70B70S#B71B71S#B72B72G#B73B73S#B74B74S#B75B75G#B76B76S#B77B77S#B78B78G#B79B79S#B80B80S#B81B81G#B82B82S#B83B83S#B84B84G#B85B85S#B86B86S#B87B87G#B88B88S#B89B89S#B90B90G#B91B91S#B92B92S#B93B93G#B94B94S#B95B95S#B96B96G#B97B97S#B98B98S#B99B99G#B100B100
TOP BOTTOM
02 Do not mirror
GF9
GF-200P-8-GP-U1
G#A1A1S#A2A2S#A3A3G#A4A4S#A5A5S#A6A6G#A7A7S#A8A8S#A9A9G#A10A10S#A11A11S#A12A12G#A13A13S#A14A14S#A15A15G#A16A16S#A17A17S#A18A18G#A19A19S#A20A20S#A21A21G#A22A22S#A23A23S#A24A24G#A25A25S#A26A26S#A27A27G#A28A28S#A29A29S#A30A30G#A31A31S#A32A32S#A33A33G#A34A34S#A35A35S#A36A36G#A37A37S#A38A38S#A39A39G#A40A40S#A41A41S#A42A42G#A43A43R#A44A44G#A45A45S#A46A46S#A47A47G#A48A48S#A49A49S#A50A50G#A51A51S#A52A52S#A53A53G#A54A54S#A55A55S#A56A56G#A57A57S#A58A58S#A59A59G#A60A60S#A61A61S#A62A62G#A63A63S#A64A64S#A65A65G#A66A66S#A67A67S#A68A68G#A69A69S#A70A70S#A71A71G#A72A72S#A73A73S#A74A74G#A75A75S#A76A76S#A77A77G#A78A78S#A79A79S#A80A80G#A81A81S#A82A82S#A83A83G#A84A84S#A85A85S#A86A86G#A87A87S#A88A88S#A89A89G#A90A90S#A91A91S#A92A92G#A93A93S#A94A94S#A95A95G#A96A96S#A97A97S#A98A98G#A99A99R#A100A100
R#B1B1G#B2B2S#B3B3S#B4B4G#B5B5S#B6B6S#B7B7G#B8B8S#B9B9S#B10B10G#B11B11S#B12B12S#B13B13G#B14B14S#B15B15S#B16B16G#B17B17S#B18B18S#B19B19G#B20B20S#B21B21S#B22B22G#B23B23S#B24B24S#B25B25G#B26B26S#B27B27S#B28B28G#B29B29S#B30B30S#B31B31G#B32B32S#B33B33S#B34B34G#B35B35S#B36B36S#B37B37G#B38B38S#B39B39S#B40B40G#B41B41S#B42B42S#B43B43G#B44B44R#B45B45G#B46B46S#B47B47S#B48B48G#B49B49S#B50B50S#B51B51G#B52B52S#B53B53S#B54B54G#B55B55S#B56B56S#B57B57G#B58B58S#B59B59S#B60B60G#B61B61S#B62B62S#B63B63G#B64B64S#B65B65S#B66B66G#B67B67S#B68B68S#B69B69G#B70B70S#B71B71S#B72B72G#B73B73S#B74B74S#B75B75G#B76B76S#B77B77S#B78B78G#B79B79S#B80B80S#B81B81G#B82B82S#B83B83S#B84B84G#B85B85S#B86B86S#B87B87G#B88B88S#B89B89S#B90B90G#B91B91S#B92B92S#B93B93G#B94B94S#B95B95S#B96B96G#B97B97S#B98B98S#B99B99G#B100B100
TOP BOTTOM
02 Do not mirror
GF10
GF-200P-8-GP-U1
G#A1A1S#A2A2S#A3A3G#A4A4S#A5A5S#A6A6G#A7A7S#A8A8S#A9A9G#A10A10S#A11A11S#A12A12G#A13A13S#A14A14S#A15A15G#A16A16S#A17A17S#A18A18G#A19A19S#A20A20S#A21A21G#A22A22S#A23A23S#A24A24G#A25A25S#A26A26S#A27A27G#A28A28S#A29A29S#A30A30G#A31A31S#A32A32S#A33A33G#A34A34S#A35A35S#A36A36G#A37A37S#A38A38S#A39A39G#A40A40S#A41A41S#A42A42G#A43A43R#A44A44G#A45A45S#A46A46S#A47A47G#A48A48S#A49A49S#A50A50G#A51A51S#A52A52S#A53A53G#A54A54S#A55A55S#A56A56G#A57A57S#A58A58S#A59A59G#A60A60S#A61A61S#A62A62G#A63A63S#A64A64S#A65A65G#A66A66S#A67A67S#A68A68G#A69A69S#A70A70S#A71A71G#A72A72S#A73A73S#A74A74G#A75A75S#A76A76S#A77A77G#A78A78S#A79A79S#A80A80G#A81A81S#A82A82S#A83A83G#A84A84S#A85A85S#A86A86G#A87A87S#A88A88S#A89A89G#A90A90S#A91A91S#A92A92G#A93A93S#A94A94S#A95A95G#A96A96S#A97A97S#A98A98G#A99A99R#A100A100
R#B1B1G#B2B2S#B3B3S#B4B4G#B5B5S#B6B6S#B7B7G#B8B8S#B9B9S#B10B10G#B11B11S#B12B12S#B13B13G#B14B14S#B15B15S#B16B16G#B17B17S#B18B18S#B19B19G#B20B20S#B21B21S#B22B22G#B23B23S#B24B24S#B25B25G#B26B26S#B27B27S#B28B28G#B29B29S#B30B30S#B31B31G#B32B32S#B33B33S#B34B34G#B35B35S#B36B36S#B37B37G#B38B38S#B39B39S#B40B40G#B41B41S#B42B42S#B43B43G#B44B44R#B45B45G#B46B46S#B47B47S#B48B48G#B49B49S#B50B50S#B51B51G#B52B52S#B53B53S#B54B54G#B55B55S#B56B56S#B57B57G#B58B58S#B59B59S#B60B60G#B61B61S#B62B62S#B63B63G#B64B64S#B65B65S#B66B66G#B67B67S#B68B68S#B69B69G#B70B70S#B71B71S#B72B72G#B73B73S#B74B74S#B75B75G#B76B76S#B77B77S#B78B78G#B79B79S#B80B80S#B81B81G#B82B82S#B83B83S#B84B84G#B85B85S#B86B86S#B87B87G#B88B88S#B89B89S#B90B90G#B91B91S#B92B92S#B93B93G#B94B94S#B95B95S#B96B96G#B97B97S#B98B98S#B99B99G#B100B100



5
5
4
4
3
3
2
2
1
1
D D
C C
B B
A A
1
2
3
4
Co-lay Co-lay
Co-lay
Co-lay
ADD=0100000(0x40)
CLOSE CN15
Co-lay
Lane0-Lane3
Lane4-Lane7
Lane8-Lane11
Lane12-Lane15
Port C
Lanes from PEB upstream
Port A
Port B
Lane0-Lane3
Lane4-Lane7
Port DPort D
MINI SAS HD on Re-timerLanes from re-timer downstream
Port C Lane8-Lane11
MINI SAS HD on PEB
Lane12-Lane15
Port B
Port A
PCIE_TX_P83PCIE_TX_P82PCIE_TX_N83PCIE_TX_N82PCIE_TX_P87PCIE_TX_P86PCIE_TX_N87PCIE_TX_N86PCIE_TX_P95PCIE_TX_P94PCIE_TX_N95PCIE_TX_N94CLK_N_2CLK_P_2CLK_N_4CLK_P_48644_SDA_R_18644_CBL_PRSNT_R_18644_USB_DP18644_USB_DN18644_USB_DN28644_CBL_PRSNT_R_28644_SDA_R_28644_USB_DP28644_USB_DN38644_CBL_PRSNT_R_38644_USB_DP38644_SDA_R_38644_USB_DN48644_SDA_R_48644_USB_DP48644_CBL_PRSNT_R_4PCIE_TX_P80PCIE_TX_N80PCIE_TX_P81PCIE_TX_N81PCIE_TX_P84PCIE_TX_N84PCIE_TX_P85PCIE_TX_N85PCIE_TX_P92PCIE_TX_N92PCIE_TX_P93PCIE_TX_N93
8644_USB_DP38644_USB_DP28644_USB_DP18644_USB_DP48644_USB_DN38644_USB_DN28644_USB_DN18644_USB_DN4PCIE_REFCLK_H2_N_RCLK_N_2PCIE_REFCLK_H3_N_RCLK_N_4HOST3_RST_N_CHOST2_RST_N_CHOST1_RST_N_CHOST4_RST_N_C
CLK_P_1_RCLK_P_2_RCLK_P_3_RCLK_P_4_RHOST1_RST_N_CPCIE_REFCLK_H2_P_RPCIE_REFCLK_H3_P_RHOST3_RST_N_CPCIE_REFCLK_H2_N_RPCIE_REFCLK_H3_N_RHOST2_RST_N_CHOST4_RST_N_CCLK_P_4PCIE_REFCLK_H3_P_RCLK_P_2PCIE_REFCLK_H2_P_RU54_P0U54_P0U54_A0U54_A1U54_A2U54_SDAU54_SCLU54_A0U54_A1U54_A2
MINISAS_CN15_B_I2C_INT#MINISAS_CN15_A_I2C_INT#MINISAS_CN15_D_I2C_INT#MINISAS_CN15_C_I2C_INT#
U54_INT_N
P3V3_STBYP3V3_STBYP3V3_STBYP3V3_STBY
P3V3_STBY
P3V3_STBYP3V3_STBYP3V3_STBYP3V3_STBY
P3V3_STBY
PCIE_TX_N8235PCIE_TX_P8235PCIE_TX_N8335PCIE_TX_P8335PCIE_RX_N83 35PCIE_RX_P83 35PCIE_RX_P82 35PCIE_RX_N82 35PCIE_TX_N8635PCIE_TX_P8635PCIE_TX_N8735PCIE_TX_P8735PCIE_RX_N87 35PCIE_RX_P87 35PCIE_RX_P86 35PCIE_RX_N86 35PCIE_TX_N9035PCIE_TX_P9035PCIE_TX_N9135PCIE_TX_P9135PCIE_RX_N91 35PCIE_RX_P91 35PCIE_RX_P90 35PCIE_RX_N90 35PCIE_TX_N9435PCIE_TX_P9435PCIE_TX_N9535PCIE_TX_P9535PCIE_RX_N95 35PCIE_RX_P95 35PCIE_RX_P94 35PCIE_RX_N94 35BMC_I2C1_MINI1_SCL12 BMC_I2C3_MINI3_SCL12BMC_I2C4_MINI4_SCL12BMC_I2C2_MINI2_SCL12CBL_PRSNT_N_113,28BMC_I2C1_MINI1_SDA12,28BMC_I2C2_MINI2_SDA12,28CBL_PRSNT_N_213,28CBL_PRSNT_N_413,28BMC_I2C4_MINI4_SDA12,28CBL_PRSNT_N_313,28BMC_I2C3_MINI3_SDA12,28CBL_PRSNT_N_113,28BMC_I2C1_MINI1_SDA12,28USB2_BMC_DP14USB2_BMC_DN14HOST1_RST_N32HOST2_RST_N32BMC_I2C2_MINI2_SDA12,28CBL_PRSNT_N_213,28CBL_PRSNT_N_313,28BMC_I2C3_MINI3_SDA12,28HOST3_RST_N32HOST4_RST_N32CBL_PRSNT_N_413,28BMC_I2C4_MINI4_SDA12,28PCIE_REFCLK_H2_N36PCIE_REFCLK_H2_P36 PCIE_REFCLK_H3_N36PCIE_REFCLK_H3_P36PCIE_TX_P8035PCIE_TX_N8035PCIE_RX_P80 35PCIE_RX_N80 35PCIE_TX_P8135PCIE_TX_N8135PCIE_RX_N81 35PCIE_RX_P81 35PCIE_RX_P84 35PCIE_RX_N84 35PCIE_TX_P8435PCIE_TX_N8435PCIE_RX_N85 35PCIE_RX_P85 35PCIE_TX_P8535PCIE_TX_N8535 PCIE_RX_P92 35PCIE_RX_N92 35PCIE_TX_P9235PCIE_TX_N9235PCIE_RX_N93 35PCIE_RX_P93 35PCIE_TX_P9335PCIE_TX_N9335PCIE_TX_P8835PCIE_TX_N8835PCIE_RX_P88 35PCIE_RX_N88 35PCIE_TX_P8935PCIE_TX_N8935PCIE_RX_N89 35PCIE_RX_P89 35
BMC_I2C1_MINI1_SDA_S 12BMC_I2C1_MINI1_SCL_S 12HOST_I2C_RESET_N14,29MINISAS_CN15_A_I2C_INT# 29MINISAS_CN15_B_I2C_INT# 29MINISAS_CN15_C_I2C_INT# 29MINISAS_CN15_D_I2C_INT# 29
Title
Size Document Number R ev
Date: Sheet o f
Lightning PMC PEB -11miniSAS HD A SFF8644Custom28 60Friday, March 31, 2017Lightning PMC PEB -1http://www.wiwynn.com8F, 90, Sec.1, Xintai 5th Rd., Xizhi Dist.,New Taipei City 22102, Taiwan (R.O.C.)
Title
Size Document Number R ev
Date: Sheet o f
Lightning PMC PEB -11miniSAS HD A SFF8644Custom28 60Friday, March 31, 2017Lightning PMC PEB -1http://www.wiwynn.com8F, 90, Sec.1, Xintai 5th Rd., Xizhi Dist.,New Taipei City 22102, Taiwan (R.O.C.)
Title
Size Document Number R ev
Date: Sheet o f
Lightning PMC PEB -11miniSAS HD A SFF8644Custom28 60Friday, March 31, 2017Lightning PMC PEB -1http://www.wiwynn.com8F, 90, Sec.1, Xintai 5th Rd., Xizhi Dist.,New Taipei City 22102, Taiwan (R.O.C.)
2 OF 5CN15BMLX-CONN144-12R-3-GP-U2TX3+BC7TX3-BC8TX2+BD7TX2-BD8TX0+BC4TX0-BC5TX1+BD4TX1-BD5SIDEBAND7BA2SIDEBAND6BD1SIDEBAND5BD2SIDEBAND4BC2SIDEBAND3BB2SIDEBAND2BC1SIDEBAND1BB1SIDEBAND0BA1RX3+BA7RX3-BA8RX2+BB7RX2-BB8RX0+BA4RX0-BA5RX1+BB4RX1-BB5GNDBA3GNDBA6GNDBA9GNDBB3GNDBB6GNDBB9GNDBC3GNDBC6GNDBC9GNDBD3GNDBD6GNDBD9
C221 SCD1U10V2KX-5GP12
R805 4K7R2F-GP12
R2931 0R2J-2-GP12
C133SCD1U10V2KX-5GP12
R2926 0R2J-2-GP12
R3040R2J-2-GPNOPOP12
 R2923 0R2J-2-GPNOPOP12
5 OF 5CN15EMLX-CONN144-12R-3-GP-U2PTH11PTH11PTH12PTH12PTH13PTH13PTH14PTH14PTH15PTH15PTH16PTH16PTH17PTH17PTH18PTH18PTH19PTH19PTH20PTH20PTH21PTH21PTH22PTH22PTH1PTH1PTH2PTH2PTH3PTH3PTH4PTH4PTH5PTH5PTH6PTH6PTH7PTH7PTH8PTH8PTH9PTH9PTH10PTH10
C130 SCD1U10V2KX-5GP12
R2952 0R2J-2-GP12
C222 SCD1U10V2KX-5GP12
R2935 0R2J-2-GP12
 R2932 0R2J-2-GP12
R2924 0R2J-2-GPNOPOP12
R6330R2J-2-GP
NOPOP
12
R7464K7R2F-GPNOPOP12
C223 SCD1U10V2KX-5GP12
R6670R2J-2-GP
NOPOP
12
4 OF 5CN15DMLX-CONN144-12R-3-GP-U2TX3+DC7TX3-DC8TX2+DD7TX2-DD8TX0+DC4TX0-DC5TX1+DD4TX1-DD5SIDEBAND7DA2SIDEBAND6DD1SIDEBAND5DD2SIDEBAND4DC2SIDEBAND3DB2SIDEBAND2DC1SIDEBAND1DB1SIDEBAND0DA1RX3+DA7RX3-DA8RX2+DB7RX2-DB8RX0+DA4RX0-DA5RX1+DB4RX1-DB5GNDDA3GNDDA6GNDDA9GNDDB3GNDDB6GNDDB9GNDDC3GNDDC6GNDDC9GNDDD3GNDDD6GNDDD9
R7484K7R2F-GPNOPOP12
R7514K7R2F-GP12
R2937 0R2J-2-GP12
R6340R2J-2-GP
NOPOP
12
R7534K7R2F-GP12
R2927 0R2J-2-GP12
C229 SCD1U10V2KX-5GP12
C224 SCD1U10V2KX-5GP12
R6680R2J-2-GP
NOPOP
12
R2960 0R2J-2-GP12
 R6370R2J-2-GP
NOPOP
12
R2951 0R2J-2-GP12
R2919 0R2J-2-GPNOPOP12
R2928 0R2J-2-GP12
 R2680R2J-2-GPNOPOP12
R6700R2J-2-GP
NOPOP
12
C225 SCD1U10V2KX-5GP12
U54TCA9554PWR-GPGND8INT#13SCL14SDA15VCC16P04P15P26P37P49P510P611P712A01A12A23
R2934 0R2J-2-GP12
R6690R2J-2-GP
NOPOP
12
R3290R2J-2-GPNOPOP12
 R2730R2J-2-GPNOPOP12
C226 SCD1U10V2KX-5GP12
R2917 0R2J-2-GPNOPOP12
R6710R2J-2-GP
NOPOP
12
R2954 0R2J-2-GP12
 R5664K7R2F-GPNOPOP12
3 OF 5CN15CMLX-CONN144-12R-3-GP-U2TX3+CC7TX3-CC8TX2+CD7TX2-CD8TX0+CC4TX0-CC5TX1+CD4TX1-CD5SIDEBAND7CA2SIDEBAND6CD1SIDEBAND5CD2SIDEBAND4CC2SIDEBAND3CB2SIDEBAND2CC1SIDEBAND1CB1SIDEBAND0CA1RX3+CA7RX3-CA8RX2+CB7RX2-CB8RX0+CA4RX0-CA5RX1+CB4RX1-CB5GNDCA3GNDCA6GNDCA9GNDCB3GNDCB6GNDCB9GNDCC3GNDCC6GNDCC9GNDCD3GNDCD6GNDCD9
R2920 0R2J-2-GPNOPOP12
C227 SCD1U10V2KX-5GP12
R2740R2J-2-GPNOPOP12
R7160R2J-2-GP
NOPOP
12
R2918 0R2J-2-GPNOPOP12
R2933 0R2J-2-GP12
C228 SCD1U10V2KX-5GP12
 R2929 0R2J-2-GP12
R5724K7R2F-GPNOPOP12
R2134K7R2F-GPNOPOP12
R2054K7R2F-GP12
 R2920R2J-2-GPNOPOP12
R2936 0R2J-2-GP12
 R2930 0R2J-2-GP12
C129 SCD1U10V2KX-5GP12
R2504K7R2F-GPNOPOP12
 R2921 0R2J-2-GPNOPOP12
R2064K7R2F-GP12
R7504K7R2F-GPNOPOP12
 R6964K7R2F-GPNOPOP12
R6320R2J-2-GP
NOPOP
12
R7524K7R2F-GP12
R2961 0R2J-2-GP12
R6444K7R2F-GP12
 R6660R2J-2-GP
NOPOP
12
R2144K7R2F-GPNOPOP12
R2074K7R2F-GP12
 R2955 0R2J-2-GP12
R3020R2J-2-GPNOPOP12
 R6994K7R2F-GPNOPOP12
R7170R2J-2-GP
NOPOP
12
R2922 0R2J-2-GPNOPOP12
R2114K7R2F-GP12
R2524K7R2F-GPNOPOP12
 R2953 0R2J-2-GP12
R3030R2J-2-GPNOPOP12
R560R2J-2-GP12
C220 SCD1U10V2KX-5GP12
 1 OF 5CN15AMLX-CONN144-12R-3-GP-U2TX3+AC7TX3-AC8TX2+AD7TX2-AD8TX0+AC4TX0-AC5TX1+AD4TX1-AD5SIDEBAND7AA2SIDEBAND6AD1SIDEBAND5AD2SIDEBAND4AC2SIDEBAND3AB2SIDEBAND2AC1SIDEBAND1AB1SIDEBAND0AA1RX3+AA7RX3-AA8RX2+AB7RX2-AB8RX0+AA4RX0-AA5RX1+AB4RX1-AB5GNDAA3GNDAA6GNDAA9GNDAB3GNDAB6GNDAB9GNDAC3GNDAC6GNDAC9GNDAD3GNDAD6GNDAD9
C132SCD047U25V2KX-GP12
R2925 0R2J-2-GP12



5
5
4
4
3
3
2
2
1
1
D D
C C
B B
A A
5
6
7
8
CLOSE CN16
Co-lay
Co-lay
Co-lay
Co-lay
Co-lay
ADD=0100000(0x40)
ADD=0100000(0x40)
CLK_P_6CLK_N_6CLK_P_8CLK_N_88644_CBL_PRSNT_R_58644_SDA_R_58644_USB_DP58644_USB_DN58644_USB_DP68644_USB_DN68644_SDA_R_68644_CBL_PRSNT_R_68644_SDA_R_78644_USB_DP78644_CBL_PRSNT_R_78644_USB_DN78644_USB_DN88644_USB_DP88644_CBL_PRSNT_R_88644_SDA_R_8HOST5_RST_N_CHOST6_RST_N_CPCIE_REFCLK_H0_P_RPCIE_REFCLK_H1_P_RHOST7_RST_N_CHOST8_RST_N_CCLK_P_8PCIE_REFCLK_H0_P_RCLK_P_5_RCLK_P_6_RCLK_P_7_RCLK_P_8_RPCIE_REFCLK_H1_P_RCLK_P_6MINISAS_CN16_A_I2C_INT#MINISAS_CN16_B_I2C_INT#MINISAS_CN16_C_I2C_INT#MINISAS_CN16_D_I2C_INT#PCIE_REFCLK_H0_N_RCLK_N_6PCIE_REFCLK_H1_N_RCLK_N_88644_USB_DP78644_USB_DP68644_USB_DP58644_USB_DP8HOST7_RST_N_CHOST6_RST_N_CHOST5_RST_N_CHOST8_RST_N_C8644_USB_DN78644_USB_DN68644_USB_DN58644_USB_DN8
PCIE_REFCLK_H0_N_RPCIE_REFCLK_H1_N_R
U55_A1U55_A2U55_A2U55_A0U55_SDAU55_SCLU55_P0U55_P0U55_A1U55_A0U56_A1U56_A2U56_A2U56_A0U56_SDAU56_SCLU56_A1U56_A0MINISAS_CN16_A_I2C_INT#MINISAS_CN16_C_I2C_INT#MINISAS_CN16_D_I2C_INT#MINISAS_CN16_B_I2C_INT#MINISAS_CN16_B_I2C_INT#MINISAS_CN16_A_I2C_INT#MINISAS_CN16_D_I2C_INT#MINISAS_CN16_C_I2C_INT#U55_INT_NU56_INT_N
P3V3_STBY
P3V3_STBYP3V3_STBYP3V3_STBY
P3V3_STBY
P3V3_STBYP3V3_STBYP3V3_STBYP3V3_STBYP3V3_STBYP3V3_STBYP3V3_STBYPCIE_RX_P14 33PCIE_RX_N14 33PCIE_RX_N15 33PCIE_RX_P15 33PCIE_TX_P633PCIE_TX_N633PCIE_TX_N733PCIE_TX_P733PCIE_TX_P233PCIE_TX_N233PCIE_TX_N333PCIE_TX_P333PCIE_TX_P1033PCIE_TX_N1033PCIE_TX_N1133PCIE_TX_P1133PCIE_TX_P1433PCIE_TX_N1433PCIE_TX_N1533PCIE_TX_P1533PCIE_RX_P2 33PCIE_RX_N2 33PCIE_RX_P3 33PCIE_RX_N3 33PCIE_RX_P6 33PCIE_RX_N6 33PCIE_RX_N7 33PCIE_RX_P7 33PCIE_RX_P10 33PCIE_RX_N10 33PCIE_RX_N11 33PCIE_RX_P11 33BMC_I2C11_MINI5_SCL12BMC_I2C12_MINI6_SCL12BMC_I2C13_MINI7_SCL12BMC_I2C14_MINI8_SCL12BMC_I2C11_MINI5_SDA12,29CBL_PRSNT_N_513,29CBL_PRSNT_N_613,29BMC_I2C12_MINI6_SDA12,29BMC_I2C13_MINI7_SDA12,29CBL_PRSNT_N_713,29BMC_I2C14_MINI8_SDA12,29CBL_PRSNT_N_813,29BMC_I2C11_MINI5_SDA12,29CBL_PRSNT_N_513,29HOST5_RST_N32CBL_PRSNT_N_613,29BMC_I2C12_MINI6_SDA12,29HOST6_RST_N32BMC_I2C13_MINI7_SDA12,29CBL_PRSNT_N_713,29HOST7_RST_N32BMC_I2C14_MINI8_SDA12,29CBL_PRSNT_N_813,29HOST8_RST_N32PCIE_REFCLK_H0_N36PCIE_REFCLK_H0_P36PCIE_REFCLK_H1_N36PCIE_REFCLK_H1_P36PCIE_RX_N0 33PCIE_RX_P0 33PCIE_TX_N033PCIE_TX_P033PCIE_RX_N1 33PCIE_RX_P1 33PCIE_TX_N133PCIE_TX_P133PCIE_RX_P4 33PCIE_RX_N4 33PCIE_TX_P433PCIE_TX_N433PCIE_RX_P5 33PCIE_RX_N5 33PCIE_TX_N533PCIE_TX_P533PCIE_TX_P833PCIE_TX_N833PCIE_RX_P8 33PCIE_RX_N8 33PCIE_TX_P933PCIE_TX_N933PCIE_RX_P9 33PCIE_RX_N9 33PCIE_TX_P1233PCIE_TX_N1233PCIE_RX_P12 33PCIE_RX_N12 33PCIE_TX_N1333PCIE_TX_P1333PCIE_RX_N13 33PCIE_RX_P13 33USB_P4_DN_BMC14USB_P4_DP_BMC14
BMC_I2C11_MINI5_SDA_S 12BMC_I2C11_MINI5_SCL_S 12HOST_I2C_RESET_N14,28BMC_I2C8_CLKBUF1_SDA 12,21BMC_I2C8_CLKBUF1_SCL 12,21MINISAS_CN15_A_I2C_INT#28MINISAS_CN15_B_I2C_INT#28MINISAS_CN15_C_I2C_INT#28MINISAS_CN15_D_I2C_INT#28TCA9554_INT_N 12
Title
Size Document Number Rev
Date: Sheet o f
Lightning PMC PEB -11miniSAS HD B SFF8644Custom29 60Friday, March 31, 2017Lightning PMC PEB -1http://www.wiwynn.com8F, 90, Sec.1, Xintai 5th Rd., Xizhi Dist.,New Taipei City 22102, Taiwan (R.O.C.)
Title
Size Document Number Rev
Date: Sheet o f
Lightning PMC PEB -11miniSAS HD B SFF8644Custom29 60Friday, March 31, 2017Lightning PMC PEB -1http://www.wiwynn.com8F, 90, Sec.1, Xintai 5th Rd., Xizhi Dist.,New Taipei City 22102, Taiwan (R.O.C.)
Title
Size Document Number Rev
Date: Sheet o f
Lightning PMC PEB -11miniSAS HD B SFF8644Custom29 60Friday, March 31, 2017Lightning PMC PEB -1http://www.wiwynn.com8F, 90, Sec.1, Xintai 5th Rd., Xizhi Dist.,New Taipei City 22102, Taiwan (R.O.C.)
R7180R2J-2-GP
NOPOP
12
U56TCA9554PWR-GPGND8INT#13SCL14SDA15VCC16P04P15P26P37P49P510P611P712A01A12A23
R4130R2J-2-GPNOPOP12
R7240R2J-2-GP
NOPOP
12
R2908 0R2J-2-GPNOPOP12
R7784K7R2F-GP12
 R7034K7R2F-GPNOPOP12
R3880R2J-2-GPNOPOP12
R2224K7R2F-GPNOPOP12
C255 SCD1U10V2KX-5GP12
5 OF 5CN16EMLX-CONN144-12R-3-GP-U2PTH11PTH11PTH12PTH12PTH13PTH13PTH14PTH14PTH15PTH15PTH16PTH16PTH17PTH17PTH18PTH18PTH19PTH19PTH20PTH20PTH21PTH21PTH22PTH22PTH1PTH1PTH2PTH2PTH3PTH3PTH4PTH4PTH5PTH5PTH6PTH6PTH7PTH7PTH8PTH8PTH9PTH9PTH10PTH10
R2910 0R2J-2-GP12
R2968 0R2J-2-GPNOPOP12
R2907 0R2J-2-GPNOPOP12
R7914K7R2F-GP12
 R7250R2J-2-GP
NOPOP
12
 R7064K7R2F-GPNOPOP12
R2544K7R2F-GPNOPOP12
R900R2J-2-GP12
C256 SCD1U10V2KX-5GP12
R2969 0R2J-2-GPNOPOP12
U55TCA9554PWR-GPGND8INT#13SCL14SDA15VCC16P04P15P26P37P49P510P611P712A01A12A23
C257 SCD1U10V2KX-5GP12
R8244K7R2F-GPNOPOP12
R2965 0R2J-2-GP12
R7260R2J-2-GP
NOPOP
12
C277 SCD1U10V2KX-5GP12
4 OF 5CN16DMLX-CONN144-12R-3-GP-U2TX3+DC7TX3-DC8TX2+DD7TX2-DD8TX0+DC4TX0-DC5TX1+DD4TX1-DD5SIDEBAND7DA2SIDEBAND6DD1SIDEBAND5DD2SIDEBAND4DC2SIDEBAND3DB2SIDEBAND2DC1SIDEBAND1DB1SIDEBAND0DA1RX3+DA7RX3-DA8RX2+DB7RX2-DB8RX0+DA4RX0-DA5RX1+DB4RX1-DB5GNDDA3GNDDA6GNDDA9GNDDB3GNDDB6GNDDB9GNDDC3GNDDC6GNDDC9GNDDD3GNDDD6GNDDD9
R7220R2J-2-GP
NOPOP
12
R2979 0R2J-2-GP12
R7190R2J-2-GP
NOPOP
12
1 OF 5CN16AMLX-CONN144-12R-3-GP-U2TX3+AC7TX3-AC8TX2+AD7TX2-AD8TX0+AC4TX0-AC5TX1+AD4TX1-AD5SIDEBAND7AA2SIDEBAND6AD1SIDEBAND5AD2SIDEBAND4AC2SIDEBAND3AB2SIDEBAND2AC1SIDEBAND1AB1SIDEBAND0AA1RX3+AA7RX3-AA8RX2+AB7RX2-AB8RX0+AA4RX0-AA5RX1+AB4RX1-AB5GNDAA3GNDAA6GNDAA9GNDAB3GNDAB6GNDAB9GNDAC3GNDAC6GNDAC9GNDAD3GNDAD6GNDAD9
R2966 0R2J-2-GP12
R8334K7R2F-GPNOPOP12
R2976 0R2J-2-GP12
 R2915 0R2J-2-GP12
R2901 0R2J-2-GPNOPOP12
2 OF 5CN16BMLX-CONN144-12R-3-GP-U2TX3+BC7TX3-BC8TX2+BD7TX2-BD8TX0+BC4TX0-BC5TX1+BD4TX1-BD5SIDEBAND7BA2SIDEBAND6BD1SIDEBAND5BD2SIDEBAND4BC2SIDEBAND3BB2SIDEBAND2BC1SIDEBAND1BB1SIDEBAND0BA1RX3+BA7RX3-BA8RX2+BB7RX2-BB8RX0+BA4RX0-BA5RX1+BB4RX1-BB5GNDBA3GNDBA6GNDBA9GNDBB3GNDBB6GNDBB9GNDBC3GNDBC6GNDBC9GNDBD3GNDBD6GNDBD9
R2962 0R2J-2-GP12
R2904 0R2J-2-GPNOPOP12
R2980 0R2J-2-GP12
R2974 0R2J-2-GP12
C135SCD047U25V2KX-GP12
R7200R2J-2-GP
NOPOP
12
C278 SCD1U10V2KX-5GP12
R2977 0R2J-2-GP12
R823 4K7R2F-GP12
R2916 0R2J-2-GP12
R2154K7R2F-GP12
R2903 0R2J-2-GPNOPOP12
R7634K7R2F-GPNOPOP12
C136SCD1U10V2KX-5GP12
C131 SCD1U10V2KX-5GP12
R7210R2J-2-GP
NOPOP
12
R2902 0R2J-2-GPNOPOP12
 R2906 0R2J-2-GPNOPOP12
R2164K7R2F-GP12
R8344K7R2F-GP12
R3320R2J-2-GPNOPOP12
 R835 4K7R2F-GP12
R2913 0R2J-2-GP12
R8384K7R2F-GPNOPOP12
R7270R2J-2-GP
NOPOP
12
R2967 0R2J-2-GP12
R2174K7R2F-GP12
R7654K7R2F-GPNOPOP12
C142SCD047U25V2KX-GP12
R2905 0R2J-2-GPNOPOP12
R2770R2J-2-GPNOPOP12
C230 SCD1U10V2KX-5GP12
R2963 0R2J-2-GP12
 R2914 0R2J-2-GP12
R7280R2J-2-GP
NOPOP
12
R3710R2J-2-GPNOPOP12
R2184K7R2F-GP12
C143SCD1U10V2KX-5GP12
 R2780R2J-2-GPNOPOP12
C231 SCD1U10V2KX-5GP12
 R5834K7R2F-GPNOPOP12
C134 SCD1U10V2KX-5GP12
R2911 0R2J-2-GP12
 R69 0R2J-2-GP12
C237 SCD1U10V2KX-5GP12
R7744K7R2F-GP12
R8004K7R2F-GPNOPOP12
R3890R2J-2-GPNOPOP12
R8364K7R2F-GP12
R3770R2J-2-GPNOPOP12
R7290R2J-2-GP
NOPOP
12
3 OF 5CN16CMLX-CONN144-12R-3-GP-U2TX3+CC7TX3-CC8TX2+CD7TX2-CD8TX0+CC4TX0-CC5TX1+CD4TX1-CD5SIDEBAND7CA2SIDEBAND6CD1SIDEBAND5CD2SIDEBAND4CC2SIDEBAND3CB2SIDEBAND2CC1SIDEBAND1CB1SIDEBAND0CA1RX3+CA7RX3-CA8RX2+CB7RX2-CB8RX0+CA4RX0-CA5RX1+CB4RX1-CB5GNDCA3GNDCA6GNDCA9GNDCB3GNDCB6GNDCB9GNDCC3GNDCC6GNDCC9GNDCD3GNDCD6GNDCD9
R2964 0R2J-2-GP12
R2194K7R2F-GPNOPOP12
R2912 0R2J-2-GP12
R8374K7R2F-GP12
C242 SCD1U10V2KX-5GP12
R7230R2J-2-GP
NOPOP
12
R2534K7R2F-GPNOPOP12
 R7024K7R2F-GPNOPOP12
R2975 0R2J-2-GP12
C254 SCD1U10V2KX-5GP12
R2909 0R2J-2-GP12



5
5
4
4
3
3
2
2
1
1
D D
C C
B B
A A
Title
Size Document Number Rev
Date: Sheet o f
Lightning PMC PEB -11RESERVEA430 60Friday, March 31, 2017Lightning PMC PEB -1http://www.wiwynn.com8F, 90, Sec.1, Xintai 5th Rd., Xizhi Dist.,New Taipei City 22102, Taiwan (R.O.C.)
Title
Size Document Number Rev
Date: Sheet o f
Lightning PMC PEB -11RESERVEA430 60Friday, March 31, 2017Lightning PMC PEB -1http://www.wiwynn.com8F, 90, Sec.1, Xintai 5th Rd., Xizhi Dist.,New Taipei City 22102, Taiwan (R.O.C.)
Title
Size Document Number Rev
Date: Sheet o f
Lightning PMC PEB -11RESERVEA430 60Friday, March 31, 2017Lightning PMC PEB -1http://www.wiwynn.com8F, 90, Sec.1, Xintai 5th Rd., Xizhi Dist.,New Taipei City 22102, Taiwan (R.O.C.)



5
5
4
4
3
3
2
2
1
1
D D
C C
B B
A A
impedance 85 ohm , series resistance R313 and R325 used 27 ohmimpedance 100 ohm , series resistance R313 and R325 used 33 ohm
Note : Layout
XTAL_X2_CLKGENXTAL_X1CLKGEN_SDACLKGEN_SCLPCIE_CLKGEN2_OE0PCIE_CLKGEN2_OE0_RPCIE_REFCLK_D_P_RPCIE_REFCLK_D_N_RCLKGEN_OE1CLKGEN_OE2CLKGEN_P2CLKGEN_N2CLKGEN_OE3CLKGEN_P3CLKGEN_N3CLKGNE_SS_ENCLKGEN_PWGDCLKGNE_SADRCLKGNE_SADR_RCLKGEN_P2_RCLKGEN_OE1_RCLKGEN_N2_RCLKGEN_OE2_RCLKGEN_P3_RCLKGEN_N3_RCLKGEN_P1_RCLKGEN_N1_RCLKGEN_OE3_RXTAL_X2XTAL_X1XTAL_X2_CLKGENP1V8_STBY
P1V8_STBY
P1V8_CLKGENP1V8_CLKGEN_AP1V8_CLKGEN_AP1V8_CLKGENP1V8_STBYP1V8_STBYP1V8_CLKGENPCIE_REFCLK_D_P 36PCIE_REFCLK_D_N 36BMC_I2C5_D_PEB_SDA11,21,23,36,46BMC_I2C5_D_PEB_SCL11,21,23,36,46I210_REFCLK_D_P 44I210_REFCLK_D_N 44
Title
Size Document Number R e v
Date: Sheet o f
Lightning PMC PEB -11CLOCK GENERATORA331 60Friday, March 31, 2017Lightning PMC PEB -1http://www.wiwynn.com8F, 90, Sec.1, Xintai 5th Rd., Xizhi Dist.,New Taipei City 22102, Taiwan (R.O.C.)
Title
Size Document Number R e v
Date: Sheet o f
Lightning PMC PEB -11CLOCK GENERATORA331 60Friday, March 31, 2017Lightning PMC PEB -1http://www.wiwynn.com8F, 90, Sec.1, Xintai 5th Rd., Xizhi Dist.,New Taipei City 22102, Taiwan (R.O.C.)
Title
Size Document Number R e v
Date: Sheet o f
Lightning PMC PEB -11CLOCK GENERATORA331 60Friday, March 31, 2017Lightning PMC PEB -1http://www.wiwynn.com8F, 90, Sec.1, Xintai 5th Rd., Xizhi Dist.,New Taipei City 22102, Taiwan (R.O.C.)
R740R2J-2-GP12
R5910KR2F-2-GP12
L10BLM18SG121TN1D-GP12
 R87 0R2J-2-GP12
R10010KR2F-2-GP
NOPOP
12
R4410KR2F-2-GP12
C712SCD1U10V2KX-5GP12
C731SC10U16V5KX-1-GP
NOPOP
12
U1969FGV0431AKLFT-GPGNDXTAL1XIN/CLKIN_252X23VDDXTAL1D84VDDREF1D85SADR/REF1D86GNDREF7GNDDIG8VDDDIG1D89SCLK_3D310SDATA_3D311OE0#12DIF013DIF0#14GND15VDDO1D816OE1#17DIF118DIF1#19GNDA20VDDA1D821DIF222DIF2#23OE2#24VDDO1D825GND26DIF327DIF3#28OE3#29GND30CKPWRGD_PD#31SS_EN_TRI32GND33
R9810KR2F-2-GP
NOPOP
12
 R3103 27R2F-GP12
R3102 27R2F-GP12
R3106 27R2F-GP12
C713SCD1U10V2KX-5GP12
 R77 0R2J-2-GP12
C719SC1U10V2KX-4-GP12
R7121MR2F-GP
NOPOP
12
 R3107 27R2F-GP12
C714SCD1U10V2KX-5GP12 TP741
R5510KR2F-2-GPNOPOP12
R9910KR2F-2-GP12 TP711TP751
C715SCD1U10V2KX-5GP12
C721SCD1U10V2KX-5GP12
R6110KR2F-2-GPNOPOP12TP781TP761
C716SCD1U10V2KX-5GP12
R6210KR2F-2-GPNOPOP12
R10110KR2F-2-GP12
C717SCD1U10V2KX-5GP12
C412SC12P50V2JN-3GP12
 R88 0R2J-2-GP12
R3108 27R2F-GP12
C720SC1U10V2KX-4-GP12
 R3109 27R2F-GP12
C718SCD1U10V2KX-5GP12
R78 0R2J-2-GP12
R3110 33R2F-3-GP12
C413SC12P50V2JN-3GP12
 R9710KR2F-2-GP12
R921R3F-GP12 TP771
R9610KR2F-2-GP
NOPOP
12 TP801
R750R2J-2-GP12
R3104 27R2F-GPNOPOP12TP811
R4510KR2F-2-GP12
X3XTAL-25MHZ-266-GP4123
 R3105 27R2F-GPNOPOP12
R6010KR2F-2-GP12
R89 0R2J-2-GP12



5
5
4
4
3
3
2
2
1
1
D D
C C
B B
A A
to PMC 8536
Reset SLIDE SW1-2: BMC reset (default)2-3: SW reset
SHUTDOWN LATCH RELEASE
B DATA to A BUS
from BMC
EVT 20151215
PVT 20161103
PM8536_RST#_ANDPE1_PERST#_RPM8536_RST#_LSPM8536_PG2_RSHUTDOWN_RELEASE
BMC_SSD_RST#0_A0SSD_PERST#0_B0SSD_PERST_Y0BMC_SSD_RST#0_A1SSD_PERST#0_B1SSD_PERST_Y1BMC_SSD_RST#0_A2SSD_PERST#0_B2SSD_PERST_Y2BMC_SSD_RST#0_A3SSD_PERST#0_B3SSD_PERST_Y3BMC_SSD_RST#0_A4SSD_PERST#0_B4SSD_PERST_Y4BMC_SSD_RST#0_A5SSD_PERST#0_B5SSD_PERST_Y5BMC_SSD_RST#0_A6SSD_PERST#0_B6SSD_PERST_Y6BMC_SSD_RST#0_A7SSD_PERST#0_B7SSD_PERST_Y7BMC_SSD_RST#0_A8SSD_PERST#0_B8SSD_PERST_Y8BMC_SSD_RST#0_A9SSD_PERST#0_B9SSD_PERST_Y9BMC_SSD_RST#0_A10SSD_PERST#0_B10SSD_PERST_Y10BMC_SSD_RST#0_A11SSD_PERST#0_B11SSD_PERST_Y11BMC_SSD_RST#0_A12SSD_PERST#0_B12SSD_PERST_Y12BMC_SSD_RST#0_A13SSD_PERST#0_B13SSD_PERST_Y13BMC_SSD_RST#0_A14SSD_PERST#0_B14SSD_PERST_Y14Q3202_DSLIDE_SW_PMC_RST#HOST5_RST_NHOST2_RST_NHOST8_RST_NHOST6_RST_NHOST7_RST_NHOST1_RST_NHOST3_RST_NHOST4_RST_NHOST5_RST_NHOST2_RST_NHOST8_RST_NHOST6_RST_NHOST7_RST_NHOST1_RST_NHOST3_RST_NHOST4_RST_NPM8536_RST#_LS_RPM8536_RST#_LSBMC_SSD_RST#0_A8BMC_SSD_RST#0_A10BMC_SSD_RST#0_A9BMC_SSD_RST#0_A11BMC_SSD_RST#0_A13BMC_SSD_RST#0_A12BMC_SSD_RST#0_A14BMC_SSD_RST#0_A0BMC_SSD_RST#0_A2BMC_SSD_RST#0_A4BMC_SSD_RST#0_A6BMC_SSD_RST#0_A1BMC_SSD_RST#0_A3BMC_SSD_RST#0_A5BMC_SSD_RST#0_A7PQ21_GADM6315_PM8536_RST#PQ22_GU81_BHOST1_RST_N_RU81_YU82_MR#U82_RST#HOST1_RST_N_RQ37_GRST_BTN#_RSLIDE_SW_PMC_RST#SLIDE_SW_PMC_RST#RST_BTN#U81_Y
P3V3_STBY
DUT_VDDOP3V3_STBY
P3V3_STBY
P3V3_STBY
P3V3_STBY
P3V3_STBY
P3V3_STBY
P3V3_STBY
P3V3_STBY
P3V3_STBY
P3V3_STBY
P3V3_STBY
P3V3_STBY
P3V3_STBY
P3V3_STBY
P3V3_STBY
P3V3_STBY
P3V3_STBYDUT_VDDOP3V3_STBY
P3V3_STBY
P3V3_STBY
P3V3_STBY
P3V3_STBY
P3V3_STBY P3V3_STBY
P3V3_STBY
P3V3_STBY P3V3_STBY
P3V3_STBYP3V3_STBYSHUTDOWN_RELEASE27HOST8_RST_N 29HOST1_RST_N 28,32HOST2_RST_N 28HOST3_RST_N 28HOST4_RST_N 28HOST5_RST_N 29HOST6_RST_N 29HOST7_RST_N 29HOST6_RST_N_LS37HOST4_RST_N_LS37HOST8_RST_N_LS37HOST2_RST_N_LS37HOST7_RST_N_LS37HOST1_RST_N_LS32,37HOST5_RST_N_LS37HOST3_RST_N_LS37
SSD_PERST#041BMC_SSD_RST#013SSD_PERST#0_R 27,41BMC_SSD_RST#113SSD_PERST#1_R 27,41SSD_PERST#141BMC_SSD_RST#213SSD_PERST#2_R 27,41SSD_PERST#241BMC_SSD_RST#313SSD_PERST#3_R 27,41SSD_PERST#341BMC_SSD_RST#413SSD_PERST#4_R 27,41SSD_PERST#441BMC_SSD_RST#513SSD_PERST#5_R 27,41SSD_PERST#541BMC_SSD_RST#613SSD_PERST#6_R 27,41SSD_PERST#641BMC_SSD_RST#713SSD_PERST#7_R 27,41SSD_PERST#741BMC_SSD_RST#813SSD_PERST#8_R 27,41SSD_PERST#841BMC_SSD_RST#913SSD_PERST#9_R 27,41SSD_PERST#941BMC_SSD_RST#1013SSD_PERST#10_R 27,41SSD_PERST#1041BMC_SSD_RST#1113SSD_PERST#11_R 27,41SSD_PERST#1141BMC_SSD_RST#1213SSD_PERST#12_R 27,41SSD_PERST#1241BMC_SSD_RST#1313SSD_PERST#13_R 27,41SSD_PERST#1341BMC_SSD_RST#1413SSD_PERST#14_R 27,41SSD_PERST#1441PM8536_RST# 36PE1_PERST#12 HOST1_RST_N28,32HOST1_RST_N_LS 32,37HB_OUT22,24,27FM_BMC_RESET#_BTN 14DP_RST_N 14,25
Title
Size Document Number R e v
Date: Sheet o f
Lightning PMC PEB -11RESETCustom32 60Friday, March 31, 2017Lightning PMC PEB -1http://www.wiwynn.com8F, 90, Sec.1, Xintai 5th Rd., Xizhi Dist.,New Taipei City 22102, Taiwan (R.O.C.)
Title
Size Document Number R e v
Date: Sheet o f
Lightning PMC PEB -11RESETCustom32 60Friday, March 31, 2017Lightning PMC PEB -1http://www.wiwynn.com8F, 90, Sec.1, Xintai 5th Rd., Xizhi Dist.,New Taipei City 22102, Taiwan (R.O.C.)
Title
Size Document Number R e v
Date: Sheet o f
Lightning PMC PEB -11RESETCustom32 60Friday, March 31, 2017Lightning PMC PEB -1http://www.wiwynn.com8F, 90, Sec.1, Xintai 5th Rd., Xizhi Dist.,New Taipei City 22102, Taiwan (R.O.C.)
R3716 1KR2F-3-GPNOPOP12
R676 100KR2F-L1-GP12
R7134K7R2F-GP12
R6734K7R2F-GP12
R32440R2J-2-GP
NOPOP12
C3215SCD1U25V2KX-2-GP12
R3710 1KR2F-3-GPNOPOP12
U81SN74LVC1G08DCKR-GPB2A1GND3Y4VCC5
R674 100KR2F-L1-GP12
R32120R2J-2-GP12
C375SCD1U25V2KX-2-GP12
R32270R2J-2-GP12
R32360R2J-2-GP12
R32390R2J-2-GP12
R6944K7R2F-GP12
R209 4K7R2F-GP12
 C374SCD1U25V2KX-2-GP12
C3205SCD1U25V2KX-2-GP12
C3208SCD1U25V2KX-2-GP12
R79100R2J-2-GP12
SC1114SCD1U16V2KX-3GP12
R3711 1KR2F-3-GPNOPOP12
R32160R2J-2-GP12
R32190R2J-2-GP12
 R7144K7R2F-GP
NOPOP
12
R140 4K7R2F-GP12
R210 4K7R2F-GP12
R32170R2J-2-GP
NOPOP
12
R32280R2J-2-GP12
R32070R2J-2-GP12
R32080R2J-2-GP
NOPOP12
R32290R2J-2-GP
NOPOP12
C241SC1U10V2KX-4-GP12
R32330R2J-2-GP12
R32030R2J-2-GP12
R32060R2J-2-GP12
 R32430R2J-2-GP12
SC1115SCD1U16V2KX-3GP12
R682 100KR2F-L1-GP12
R79050R2J-2-GP12
R79820R2J-2-GP12
R141 4K7R2F-GP12
 R32420R2J-2-GP12
U67SN74LVC1G08DCKR-GPB2A1GND3Y4VCC5
U72SN74LVC1G08DCKR-GPB2A1GND3Y4VCC5
R79020R2J-2-GP12
R32230R2J-2-GP
NOPOP12
R678 100KR2F-L1-GP12
U75SN74LVC1G08DCKR-GPB2A1GND3Y4VCC5
U76SN74LVC1G08DCKR-GPB2A1GND3Y4VCC5
R32140R2J-2-GP
NOPOP12
R675 100KR2F-L1-GP12
R3712 1KR2F-3-GPNOPOP12
R32220R2J-2-GP12
R32130R2J-2-GP12
R7917 0R2J-2-GP12
R32350R2J-2-GP
NOPOP12
R79070R2J-2-GP12
R271 4K7R2F-GP12
 C373SCD1U25V2KX-2-GP12
R142 4K7R2F-GP12
R32050R2J-2-GP
NOPOP12
U65SN74LVC1G08DCKR-GPB2A1GND3Y4VCC5
 U74SN74LVC1G08DCKR-GPB2A1GND3Y4VCC5
R79040R2J-2-GP12
R32410R2J-2-GP
NOPOP12
C3204SCD1U25V2KX-2-GP12
C3209SCD1U25V2KX-2-GP12
U77SN74LVC1G08DCKR-GPB2A1GND3Y4VCC5
U47SN74LVC1G08DCKR-GPB2A1GND3Y4VCC5
 R3713 1KR2F-3-GPNOPOP12
R6414K7R2F-GP12
C3212SCD1U25V2KX-2-GP12
C3213SCD1U25V2KX-2-GP12
R276 4K7R2F-GP12
 U79ADM6315-29D2ARTZ-GPGND1RESET#2MR#3VCC4
U6SNLVC8T245DGVR-GPA13A24A35A46A57A68A79A810B121B220B319B418B517B616B715B814VCCA1DIR2VCCB24VCCB23GND11GND12GND13OE#22
Q372N7002K-1-GPGDS
R32180R2J-2-GP12
R32210R2J-2-GP12
R32090R2J-2-GP12
R32300R2J-2-GP12
R143 4K7R2F-GP12
 R3714 1KR2F-3-GPNOPOP12
U82ADM6315-26D3ARTZR7-4-GPGND1RESET#2MR#3VCC4
R32010R2J-2-GP12
R272 4K7R2F-GP12
C266SCD1U16V2JX-1-GP12
 R681 100KR2F-L1-GP12
SW20SW-SLIDE74-GP123NP1NP2
R32450R2J-2-GP12
R6894K7R2F-GP12
 SC1116SCD1U16V2KX-3GP12
R6654K7R2F-GP12
R677 100KR2F-L1-GP12
C3211SCD1U25V2KX-2-GP12
C3202SCD1U25V2KX-2-GP12
U64SN74LVC1G08DCKR-GPB2A1GND3Y4VCC5
R32260R2J-2-GP
NOPOP12
 C3214SCD1U25V2KX-2-GP12
R144 4K7R2F-GP12
C3201SCD1U25V2KX-2-GP12
R32250R2J-2-GP12
 R79090R2J-2-GP
NOPOP
12
R79060R2J-2-GP12
 PQ21AO3400-GP-UGDS
R32100R2J-2-GP12
SW1SW-TACT-4P-196-GP1234
R32340R2J-2-GP12
R32150R2J-2-GP12
R32240R2J-2-GP12
R32370R2J-2-GP12
R3715 1KR2F-3-GPNOPOP12
R32200R2J-2-GP
NOPOP12
SW5PUSH-SW132-GP12345NP1NP2
R6974K7R2F-GP12
R32110R2J-2-GP
NOPOP12
R3709 1KR2F-3-GPNOPOP12
U69SN74LVC1G08DCKR-GPB2A1GND3Y4VCC5
U70SN74LVC1G08DCKR-GPB2A1GND3Y4VCC5
U66SN74LVC1G08DCKR-GPB2A1GND3Y4VCC5
R146 4K7R2F-GP12
 U73SN74LVC1G08DCKR-GPB2A1GND3Y4VCC5
R32020R2J-2-GP
NOPOP12
 U78SN74LVC1G08DCKR-GPB2A1GND3Y4VCC5
R32320R2J-2-GP
NOPOP
12
R3725 1KR2F-3-GPNOPOP12
C370SCD1U25V2KX-2-GP12
R145 4K7R2F-GP12
 R32310R2J-2-GP12
R32040R2J-2-GP12
 C271SC1U10V2KX-4-GP12
R157 4K7R2F-GP12
 R32400R2J-2-GP12
R32380R2J-2-GP
NOPOP
12
PQ22AO3400-GP-UGDS
Q32022N7002K-1-GPGDS
R147 4K7R2F-GP12
U68SN74LVC1G08DCKR-GPB2A1GND3Y4VCC5
U71SN74LVC1G08DCKR-GPB2A1GND3Y4VCC5
R79080R2J-2-GP12
 R680 100KR2F-L1-GP12
C3206SCD1U25V2KX-2-GP12
C3207SCD1U25V2KX-2-GP12
R79030R2J-2-GP12
C3203SCD1U25V2KX-2-GP12
R158 4K7R2F-GP12
 C3210SCD1U25V2KX-2-GP12



5
5
4
4
3
3
2
2
1
1
D D
C C
B B
A A
stack0 -> miniSAS HD B(CN16) stack1 -> 200 pin(GF10)
close to G/F close to G/F
PCIE_TX_CAP_P8PCIE_TX_CAP_N8PCIE_TX_CAP_P9PCIE_TX_CAP_N9PCIE_TX_CAP_P10PCIE_TX_CAP_N10PCIE_TX_CAP_N0PCIE_TX_CAP_P0PCIE_TX_CAP_P11PCIE_TX_CAP_N11PCIE_TX_CAP_P12PCIE_TX_CAP_N12PCIE_TX_CAP_P13PCIE_TX_CAP_N13PCIE_TX_CAP_P14PCIE_TX_CAP_N14PCIE_TX_CAP_N1PCIE_TX_CAP_P1PCIE_TX_CAP_P2PCIE_TX_CAP_N2PCIE_TX_CAP_P15PCIE_TX_CAP_N15PCIE_TX_CAP_P3PCIE_TX_CAP_N3PCIE_TX_CAP_P4PCIE_TX_CAP_N4PCIE_TX_CAP_P5PCIE_TX_CAP_N5PCIE_TX_CAP_P6PCIE_TX_CAP_N6PCIE_TX_CAP_P7PCIE_TX_CAP_N7PCIE_TX_CAP_P16PCIE_TX_CAP_N16PCIE_TX_CAP_P17PCIE_TX_CAP_N17PCIE_TX_CAP_N18PCIE_TX_CAP_P18PCIE_TX_CAP_N19PCIE_TX_CAP_P19PCIE_TX_CAP_N20PCIE_TX_CAP_P20PCIE_TX_CAP_N21PCIE_TX_CAP_P21PCIE_TX_CAP_N22PCIE_TX_CAP_P22PCIE_TX_CAP_N23PCIE_TX_CAP_P23PCIE_TX_CAP_N24PCIE_TX_CAP_P24PCIE_TX_CAP_N25PCIE_TX_CAP_P25PCIE_TX_CAP_N26PCIE_TX_CAP_P26PCIE_TX_CAP_N27PCIE_TX_CAP_P27PCIE_TX_CAP_N28PCIE_TX_CAP_P28PCIE_TX_CAP_N29PCIE_TX_CAP_P29PCIE_TX_CAP_N30PCIE_TX_CAP_P30PCIE_TX_CAP_N31PCIE_TX_CAP_P31PCIE_TX_P8 29PCIE_TX_N8 29PCIE_TX_P9 29PCIE_TX_N9 29PCIE_TX_P10 29PCIE_TX_N10 29PCIE_TX_N11 29PCIE_TX_P11 29PCIE_TX_P12 29PCIE_TX_N12 29PCIE_TX_N13 29PCIE_TX_P13 29PCIE_TX_N0 29PCIE_TX_P0 29PCIE_TX_P14 29PCIE_TX_N14 29PCIE_TX_N1 29PCIE_TX_P1 29PCIE_TX_P2 29PCIE_TX_N15 29PCIE_TX_N2 29PCIE_TX_P15 29PCIE_TX_P3 29PCIE_TX_N3 29PCIE_TX_P4 29PCIE_TX_N4 29PCIE_TX_P5 29PCIE_TX_N5 29PCIE_RX_N029PCIE_RX_P029PCIE_RX_N129PCIE_RX_P129PCIE_RX_P229PCIE_RX_N229PCIE_RX_N329PCIE_RX_P329PCIE_RX_P429PCIE_RX_N429PCIE_RX_N529PCIE_RX_P529PCIE_RX_P629PCIE_RX_N629PCIE_RX_N729PCIE_RX_P729PCIE_RX_P829PCIE_RX_N829PCIE_RX_P929PCIE_RX_N929PCIE_RX_P1029PCIE_RX_N1029PCIE_RX_N1129PCIE_RX_P1129PCIE_RX_P1229PCIE_RX_N1229PCIE_RX_N1329PCIE_RX_P1329PCIE_RX_P1429PCIE_RX_N1429PCIE_RX_N1529PCIE_RX_P1529PCIE_TX_P6 29PCIE_TX_N6 29PCIE_TX_N7 29PCIE_TX_P7 29PCIE_RX_P1827PCIE_RX_N1827PCIE_RX_N1927PCIE_RX_P1927PCIE_RX_P2027PCIE_RX_N2027PCIE_RX_N2127PCIE_RX_P2127PCIE_RX_P2227PCIE_RX_N2227PCIE_RX_N2327PCIE_RX_P2327PCIE_RX_N2427PCIE_RX_P2427PCIE_TX_N16 27PCIE_TX_P16 27PCIE_RX_P2527PCIE_RX_N2527PCIE_TX_N17 27PCIE_TX_P17 27PCIE_RX_N2627PCIE_RX_P2627PCIE_RX_P2727PCIE_RX_N2727PCIE_RX_P2827PCIE_RX_N2827PCIE_TX_P18 27PCIE_TX_N18 27PCIE_RX_N2927PCIE_RX_P2927PCIE_RX_P3027PCIE_RX_N3027PCIE_RX_P3127PCIE_RX_N3127PCIE_TX_P19 27PCIE_TX_N19 27PCIE_TX_P20 27PCIE_TX_N20 27PCIE_TX_N21 27PCIE_TX_P21 27PCIE_TX_P22 27PCIE_TX_N22 27PCIE_TX_N23 27PCIE_TX_P23 27PCIE_TX_P24 27PCIE_TX_N24 27PCIE_TX_N25 27PCIE_TX_P25 27PCIE_TX_N26 27PCIE_TX_P26 27PCIE_TX_N27 27PCIE_TX_P27 27PCIE_TX_P28 27PCIE_TX_N28 27PCIE_TX_N29 27PCIE_TX_P29 27PCIE_TX_P30 27PCIE_TX_N30 27PCIE_TX_N31 27PCIE_TX_P31 27PCIE_RX_P1627PCIE_RX_N1627PCIE_RX_N1727PCIE_RX_P1727
Title
Size Document Number R e v
Date: Sheet o f
Lightning PMC PEB -11PM8536 PCIE STACK 0-1A333 60Friday, March 31, 2017Lightning PMC PEB -1http://www.wiwynn.com8F, 90, Sec.1, Xintai 5th Rd., Xizhi Dist.,New Taipei City 22102, Taiwan (R.O.C.)
Title
Size Document Number R e v
Date: Sheet o f
Lightning PMC PEB -11PM8536 PCIE STACK 0-1A333 60Friday, March 31, 2017Lightning PMC PEB -1http://www.wiwynn.com8F, 90, Sec.1, Xintai 5th Rd., Xizhi Dist.,New Taipei City 22102, Taiwan (R.O.C.)
Title
Size Document Number R e v
Date: Sheet o f
Lightning PMC PEB -11PM8536 PCIE STACK 0-1A333 60Friday, March 31, 2017Lightning PMC PEB -1http://www.wiwynn.com8F, 90, Sec.1, Xintai 5th Rd., Xizhi Dist.,New Taipei City 22102, Taiwan (R.O.C.)
C77 SCD22U10V2KX-1GP12
C6 SCD22U10V2KX-1GP12
C26 SCD22U10V2KX-1GP12
C53 SCD22U10V2KX-1GP12
 C62 SCD22U10V2KX-1GP12
C21 SCD22U10V2KX-1GP12
C49 SCD22U10V2KX-1GP12
C12 SCD22U10V2KX-1GP12
 C59 SCD22U10V2KX-1GP12
C46 SCD22U10V2KX-1GP12
 C71 SCD22U10V2KX-1GP12
C68 SCD22U10V2KX-1GP12
C76 SCD22U10V2KX-1GP12
C95 SCD22U10V2KX-1GP12
1 OF 13U1A
PM8546A-FEIP-GPRX0_NU37RX0_PU36RX1_NT36RX1_PT35RX2_NR37RX2_PR36RX3_NP36RX3_PP35RX4_NN37RX4_PN36RX5_NM36RX5_PM35RX6_NL37RX6_PL36RX7_NK36RX7_PK35RX8_ND33RX8_PE33RX9_NE32RX9_PF32RX10_ND31RX10_PE31RX11_NE30RX11_PF30RX12_ND29RX12_PE29RX13_NE28RX13_PF28RX14_ND27RX14_PE27RX15_NE26RX15_PF26TX0_NH37TX0_PH36TX1_NG36TX1_PG35TX2_NF37TX2_PF36TX3_NE36TX3_PE35TX4_ND37TX4_PD36TX5_NC36TX5_PC35TX6_NB37TX6_PB36TX7_NA36TX7_PA35TX8_NA33TX8_PB33TX9_NB32TX9_PC32TX10_NA31TX10_PB31TX11_NB30TX11_PC30TX12_NA29TX12_PB29TX13_NB28TX13_PC28TX14_NA27TX14_PB27TX15_NB26TX15_PC26
C92 SCD22U10V2KX-1GP12
C57 SCD22U10V2KX-1GP12
C45 SCD22U10V2KX-1GP12
 C54 SCD22U10V2KX-1GP12
C13 SCD22U10V2KX-1GP12
C24 SCD22U10V2KX-1GP12
 C74 SCD22U10V2KX-1GP12
C93 SCD22U10V2KX-1GP12
C9 SCD22U10V2KX-1GP12
 C60 SCD22U10V2KX-1GP12
C19 SCD22U10V2KX-1GP12
 C63 SCD22U10V2KX-1GP12
C22 SCD22U10V2KX-1GP12
 C56 SCD22U10V2KX-1GP12
C23 SCD22U10V2KX-1GP12
C10 SCD22U10V2KX-1GP12
C7 SCD22U10V2KX-1GP12
 C69 SCD22U10V2KX-1GP12
C80 SCD22U10V2KX-1GP12
C66 SCD22U10V2KX-1GP12
C1 SCD22U10V2KX-1GP12
C11 SCD22U10V2KX-1GP12
2 OF 13
PM8546A-FEIP-GP
U1BRX16_ND24RX16_PE24RX17_NE23RX17_PF23RX18_ND22RX18_PE22RX19_NE21RX19_PF21RX20_ND20RX20_PE20RX21_NE19RX21_PF19RX22_ND18RX22_PE18RX23_NE17RX23_PF17RX24_ND15RX24_PE15RX25_NE14RX25_PF14RX26_ND13RX26_PE13RX27_NE12RX27_PF12RX28_ND11RX28_PE11RX29_NE10RX29_PF10RX30_ND9RX30_PE9RX31_NE8RX31_PF8TX16_NA24TX16_PB24TX17_NB23TX17_PC23TX18_NA22TX18_PB22TX19_NB21TX19_PC21TX20_NA20TX20_PB20TX21_NB19TX21_PC19TX22_NA18TX22_PB18TX23_NB17TX23_PC17TX24_NA15TX24_PB15TX25_NB14TX25_PC14TX26_NA13TX26_PB13TX27_NB12TX27_PC12TX28_NA11TX28_PB11TX29_NB10TX29_PC10TX30_NA9TX30_PB9TX31_NB8TX31_PC8
C55 SCD22U10V2KX-1GP12
C72 SCD22U10V2KX-1GP12
C50 SCD22U10V2KX-1GP12
C17 SCD22U10V2KX-1GP12
 C91 SCD22U10V2KX-1GP12
C75 SCD22U10V2KX-1GP12
C67 SCD22U10V2KX-1GP12
C61 SCD22U10V2KX-1GP12
C20 SCD22U10V2KX-1GP12
C48 SCD22U10V2KX-1GP12
 C78 SCD22U10V2KX-1GP12
C52 SCD22U10V2KX-1GP12
C2 SCD22U10V2KX-1GP12
 C58 SCD22U10V2KX-1GP12
C25 SCD22U10V2KX-1GP12
 C64 SCD22U10V2KX-1GP12
C14 SCD22U10V2KX-1GP12
C51 SCD22U10V2KX-1GP12
 C94 SCD22U10V2KX-1GP12
C70 SCD22U10V2KX-1GP12
C8 SCD22U10V2KX-1GP12
C16 SCD22U10V2KX-1GP12
 C79 SCD22U10V2KX-1GP12
C73 SCD22U10V2KX-1GP12
C18 SCD22U10V2KX-1GP12
 C65 SCD22U10V2KX-1GP12
C47 SCD22U10V2KX-1GP12
C15 SCD22U10V2KX-1GP12



5
5
4
4
3
3
2
2
1
1
D D
C C
B B
A A
stack2 -> 200 pin(GF10,9) stack3 -> 200 pin(GF9,8)
close to G/F close to G/F
PCIE_TX_CAP_N32PCIE_TX_CAP_P32PCIE_TX_CAP_N33PCIE_TX_CAP_P33PCIE_TX_CAP_N34PCIE_TX_CAP_P34PCIE_TX_CAP_N35PCIE_TX_CAP_P35PCIE_TX_CAP_N36PCIE_TX_CAP_P36PCIE_TX_CAP_N37PCIE_TX_CAP_P37PCIE_TX_CAP_N38PCIE_TX_CAP_P38PCIE_TX_CAP_N39PCIE_TX_CAP_P39PCIE_TX_CAP_N40PCIE_TX_CAP_P40PCIE_TX_CAP_N41PCIE_TX_CAP_P41PCIE_TX_CAP_N42PCIE_TX_CAP_P42PCIE_TX_CAP_N43PCIE_TX_CAP_P43PCIE_TX_CAP_N44PCIE_TX_CAP_P44PCIE_TX_CAP_N45PCIE_TX_CAP_P45PCIE_TX_CAP_N46PCIE_TX_CAP_P46PCIE_TX_CAP_N47PCIE_TX_CAP_P47PCIE_TX_CAP_P60PCIE_TX_CAP_N60PCIE_TX_CAP_P61PCIE_TX_CAP_N61PCIE_TX_CAP_P62PCIE_TX_CAP_N62PCIE_TX_CAP_P63PCIE_TX_CAP_N63PCIE_TX_CAP_P48PCIE_TX_CAP_N48PCIE_TX_CAP_P49PCIE_TX_CAP_N49PCIE_TX_CAP_P50PCIE_TX_CAP_N50PCIE_TX_CAP_P51PCIE_TX_CAP_N51PCIE_TX_CAP_P52PCIE_TX_CAP_N52PCIE_TX_CAP_P53PCIE_TX_CAP_N53PCIE_TX_CAP_P54PCIE_TX_CAP_N54PCIE_TX_CAP_P55PCIE_TX_CAP_N55PCIE_TX_CAP_P56PCIE_TX_CAP_N56PCIE_TX_CAP_P57PCIE_TX_CAP_N57PCIE_TX_CAP_P58PCIE_TX_CAP_N58PCIE_TX_CAP_P59PCIE_TX_CAP_N59PCIE_TX_N32 27PCIE_TX_P32 27PCIE_RX_N3227PCIE_RX_P3227PCIE_TX_N33 27PCIE_TX_P33 27PCIE_RX_N3327PCIE_RX_P3327PCIE_TX_P34 27PCIE_TX_N34 27PCIE_RX_P3427PCIE_RX_N3427PCIE_TX_N35 27PCIE_RX_N3527PCIE_RX_P3527PCIE_TX_P35 27PCIE_TX_N36 27PCIE_RX_P3627PCIE_RX_N3627PCIE_TX_P36 27PCIE_RX_P3727PCIE_TX_N37 27PCIE_TX_P37 27PCIE_RX_N3727PCIE_RX_P3827PCIE_TX_N38 27PCIE_TX_P38 27PCIE_RX_N3827PCIE_RX_P3927PCIE_TX_P39 27PCIE_RX_N3927PCIE_TX_N39 27PCIE_TX_P40 27PCIE_RX_P4027PCIE_RX_N4027PCIE_TX_N40 27PCIE_RX_N4127PCIE_TX_P41 27PCIE_RX_P4127PCIE_TX_N41 27PCIE_RX_N4227PCIE_TX_P42 27PCIE_TX_N42 27PCIE_RX_P4227PCIE_RX_N4327PCIE_TX_N43 27PCIE_RX_P4327PCIE_TX_P43 27PCIE_TX_N44 27PCIE_RX_N4427PCIE_RX_P4427PCIE_TX_P44 27PCIE_RX_P4527PCIE_TX_N45 27PCIE_RX_N4527PCIE_TX_P45 27PCIE_RX_P4627PCIE_TX_N46 27PCIE_TX_P46 27PCIE_RX_N4627PCIE_RX_P4727PCIE_TX_P47 27PCIE_RX_N4727PCIE_TX_N47 27PCIE_RX_P6027PCIE_RX_N6027PCIE_TX_P60 27PCIE_TX_N60 27PCIE_RX_P6127PCIE_RX_N6127PCIE_TX_P61 27PCIE_TX_N61 27PCIE_RX_P6227PCIE_RX_N6227PCIE_TX_P62 27PCIE_TX_N62 27PCIE_RX_P6327PCIE_RX_N6327PCIE_TX_N63 27PCIE_TX_P63 27PCIE_RX_P4827PCIE_RX_N4827PCIE_TX_P48 27PCIE_TX_N48 27PCIE_RX_P4927PCIE_RX_N4927PCIE_TX_N49 27PCIE_TX_P49 27PCIE_RX_P5027PCIE_RX_N5027PCIE_TX_N50 27PCIE_TX_P50 27PCIE_RX_P5127PCIE_RX_N5127PCIE_TX_N51 27PCIE_TX_P51 27PCIE_RX_P5227PCIE_RX_N5227PCIE_TX_N52 27PCIE_TX_P52 27PCIE_RX_P5327PCIE_RX_N5327PCIE_TX_N53 27PCIE_TX_P53 27PCIE_RX_N5427PCIE_RX_P5427PCIE_TX_N54 27PCIE_TX_P54 27PCIE_RX_N5527PCIE_RX_P5527PCIE_TX_P55 27PCIE_TX_N55 27PCIE_RX_N5627PCIE_RX_P5627PCIE_TX_N56 27PCIE_TX_P56 27PCIE_RX_N5727PCIE_RX_P5727PCIE_TX_P57 27PCIE_TX_N57 27PCIE_RX_P5827PCIE_RX_N5827PCIE_TX_P58 27PCIE_TX_N58 27PCIE_RX_P5927PCIE_RX_N5927PCIE_TX_P59 27PCIE_TX_N59 27
Title
Size Document Number R e v
Date: Sheet o f
Lightning PMC PEB -11PM8536 PCIE STACK 2-3A334 60Friday, March 31, 2017Lightning PMC PEB -1http://www.wiwynn.com8F, 90, Sec.1, Xintai 5th Rd., Xizhi Dist.,New Taipei City 22102, Taiwan (R.O.C.)
Title
Size Document Number R e v
Date: Sheet o f
Lightning PMC PEB -11PM8536 PCIE STACK 2-3A334 60Friday, March 31, 2017Lightning PMC PEB -1http://www.wiwynn.com8F, 90, Sec.1, Xintai 5th Rd., Xizhi Dist.,New Taipei City 22102, Taiwan (R.O.C.)
Title
Size Document Number R e v
Date: Sheet o f
Lightning PMC PEB -11PM8536 PCIE STACK 2-3A334 60Friday, March 31, 2017Lightning PMC PEB -1http://www.wiwynn.com8F, 90, Sec.1, Xintai 5th Rd., Xizhi Dist.,New Taipei City 22102, Taiwan (R.O.C.)
C250 SCD22U10V2KX-1GP12
C139 SCD22U10V2KX-1GP12
C114 SCD22U10V2KX-1GP12
 C149 SCD22U10V2KX-1GP12
C344 SCD22U10V2KX-1GP12
C106 SCD22U10V2KX-1GP12
 C260 SCD22U10V2KX-1GP12
C342 SCD22U10V2KX-1GP12
C127 SCD22U10V2KX-1GP12
 C161 SCD22U10V2KX-1GP12
C313 SCD22U10V2KX-1GP12
4 OF 13
PM8546A-FEIP-GP
U1DRX48_NY5RX48_PY6RX49_NAA4RX49_PAA5RX50_NAB5RX50_PAB6RX51_NAC4RX51_PAC5RX52_NAD5RX52_PAD6RX53_NAE4RX53_PAE5RX54_NAF5RX54_PAF6RX55_NAG4RX55_PAG5RX56_NAJ5RX56_PAJ6RX57_NAK4RX57_PAK5RX58_NAL5RX58_PAL6RX59_NAM4RX59_PAM5RX60_NAN5RX60_PAN6RX61_NAP4RX61_PAP5RX62_NAR5RX62_PAR6RX63_NAT4RX63_PAT5TX48_NY2TX48_PY3TX49_NAA1TX49_PAA2TX50_NAB2TX50_PAB3TX51_NAC1TX51_PAC2TX52_NAD2TX52_PAD3TX53_NAE1TX53_PAE2TX54_NAF2TX54_PAF3TX55_NAG1TX55_PAG2TX56_NAJ2TX56_PAJ3TX57_NAK1TX57_PAK2TX58_NAL2TX58_PAL3TX59_NAM1TX59_PAM2TX60_NAN2TX60_PAN3TX61_NAP1TX61_PAP2TX62_NAR2TX62_PAR3TX63_NAT1TX63_PAT2
C251 SCD22U10V2KX-1GP12
C119 SCD22U10V2KX-1GP12
 C165 SCD22U10V2KX-1GP12
C97 SCD22U10V2KX-1GP12
 C141 SCD22U10V2KX-1GP12
C111 SCD22U10V2KX-1GP12
C103 SCD22U10V2KX-1GP12
 C315 SCD22U10V2KX-1GP12
C125 SCD22U10V2KX-1GP12
C121 SCD22U10V2KX-1GP12
 C147 SCD22U10V2KX-1GP12
C169 SCD22U10V2KX-1GP12
C117 SCD22U10V2KX-1GP12
C105 SCD22U10V2KX-1GP12
C113 SCD22U10V2KX-1GP12
C109 SCD22U10V2KX-1GP12
C101 SCD22U10V2KX-1GP12
C123 SCD22U10V2KX-1GP12
C115 SCD22U10V2KX-1GP12
C107 SCD22U10V2KX-1GP12
C99 SCD22U10V2KX-1GP12
 C138 SCD22U10V2KX-1GP12
C128 SCD22U10V2KX-1GP12
C156 SCD22U10V2KX-1GP12
C150 SCD22U10V2KX-1GP12
C148 SCD22U10V2KX-1GP12
C343 SCD22U10V2KX-1GP12
C341 SCD22U10V2KX-1GP12
3 OF 13
PM8546A-FEIP-GP
U1CRX32_NB4RX32_PB5RX33_NC5RX33_PC6RX34_ND4RX34_PD5RX35_NE5RX35_PE6RX36_NF4RX36_PF5RX37_NG5RX37_PG6RX38_NH4RX38_PH5RX39_NJ5RX39_PJ6RX40_NL4RX40_PL5RX41_NM5RX41_PM6RX42_NN4RX42_PN5RX43_NP5RX43_PP6RX44_NR4RX44_PR5RX45_NT5RX45_PT6RX46_NU4RX46_PU5RX47_NV5RX47_PV6TX32_NB1TX32_PB2TX33_NC2TX33_PC3TX34_ND1TX34_PD2TX35_NE2TX35_PE3TX36_NF1TX36_PF2TX37_NG2TX37_PG3TX38_NH1TX38_PH2TX39_NJ2TX39_PJ3TX40_NL1TX40_PL2TX41_NM2TX41_PM3TX42_NN1TX42_PN2TX43_NP2TX43_PP3TX44_NR1TX44_PR2TX45_NT2TX45_PT3TX46_NU1TX46_PU2TX47_NV2TX47_PV3
C126 SCD22U10V2KX-1GP12
C118 SCD22U10V2KX-1GP12
 C137 SCD22U10V2KX-1GP12
C164 SCD22U10V2KX-1GP12
C160 SCD22U10V2KX-1GP12
C157 SCD22U10V2KX-1GP12
C140 SCD22U10V2KX-1GP12
C110 SCD22U10V2KX-1GP12
 C154 SCD22U10V2KX-1GP12
C124 SCD22U10V2KX-1GP12
 C314 SCD22U10V2KX-1GP12
C102 SCD22U10V2KX-1GP12
C120 SCD22U10V2KX-1GP12
 C144 SCD22U10V2KX-1GP12
C168 SCD22U10V2KX-1GP12
C116 SCD22U10V2KX-1GP12
 C252 SCD22U10V2KX-1GP12
C112 SCD22U10V2KX-1GP12
C100 SCD22U10V2KX-1GP12
C108 SCD22U10V2KX-1GP12
C98 SCD22U10V2KX-1GP12
C104 SCD22U10V2KX-1GP12
C96 SCD22U10V2KX-1GP12
 C273 SCD22U10V2KX-1GP12
C122 SCD22U10V2KX-1GP12



5
5
4
4
3
3
2
2
1
1
D D
C C
B B
A A
stack4 -> 200 pin(GF8) stack5 -> miniSAS HD A(CN15)close to G/F close to G/F
C368/C367close to U40
PCIE_TX_CAP_N65PCIE_TX_CAP_P65PCIE_TX_CAP_N66PCIE_TX_CAP_P66PCIE_TX_CAP_N67PCIE_TX_CAP_P67PCIE_TX_CAP_N68PCIE_TX_CAP_P68PCIE_TX_CAP_N69PCIE_TX_CAP_P69PCIE_TX_CAP_N70PCIE_TX_CAP_P70PCIE_TX_CAP_N71PCIE_TX_CAP_P71PCIE_TX_CAP_N72PCIE_TX_CAP_P72PCIE_TX_CAP_N73PCIE_TX_CAP_P73PCIE_TX_CAP_N74PCIE_TX_CAP_P74PCIE_TX_CAP_N75PCIE_TX_CAP_P75PCIE_TX_CAP_N76PCIE_RX_N76PCIE_RX_P76PCIE_TX_CAP_P76PCIE_TX_N76PCIE_TX_P76PCIE_TX_CAP_N64PCIE_TX_CAP_P64PCIE_TX_CAP_N80PCIE_TX_CAP_P80PCIE_TX_CAP_N81PCIE_TX_CAP_P81PCIE_TX_CAP_N82PCIE_TX_CAP_P82PCIE_TX_CAP_N83PCIE_TX_CAP_P83PCIE_TX_CAP_N84PCIE_TX_CAP_P84PCIE_TX_CAP_N85PCIE_TX_CAP_P85PCIE_TX_CAP_N86PCIE_TX_CAP_P86PCIE_TX_CAP_N87PCIE_TX_CAP_P87PCIE_TX_CAP_N88PCIE_TX_CAP_P88PCIE_TX_CAP_N89PCIE_TX_CAP_P89PCIE_TX_CAP_N90PCIE_TX_CAP_P90PCIE_TX_CAP_N91PCIE_TX_CAP_P91PCIE_TX_CAP_N92PCIE_TX_CAP_P92PCIE_TX_CAP_N93PCIE_TX_CAP_P93PCIE_TX_CAP_N94PCIE_TX_CAP_P94PCIE_TX_CAP_N95PCIE_TX_CAP_P95PCIE_TX_CAP_N78PCIE_TX_CAP_P78PCIE_RX_P6527PCIE_TX_P65 27PCIE_TX_N65 27PCIE_RX_N6527PCIE_RX_P6627PCIE_TX_N66 27PCIE_TX_P66 27PCIE_RX_N6627PCIE_RX_P6727PCIE_TX_P67 27PCIE_TX_N67 27PCIE_RX_N6727PCIE_RX_N6827PCIE_RX_P6827PCIE_TX_N68 27PCIE_TX_P68 27PCIE_RX_N6927PCIE_TX_P69 27PCIE_RX_P6927PCIE_TX_N69 27PCIE_RX_N7027PCIE_TX_P70 27PCIE_RX_P7027PCIE_TX_N70 27PCIE_RX_N7127PCIE_TX_P71 27PCIE_TX_N71 27PCIE_RX_P7127PCIE_RX_N7227PCIE_TX_N72 27PCIE_TX_P72 27PCIE_RX_P7227PCIE_RX_N7327PCIE_TX_P73 27PCIE_RX_P7327PCIE_TX_N73 27PCIE_TX_P74 27PCIE_RX_P7427PCIE_RX_N7427PCIE_TX_N74 27PCIE_TX_P75 27PCIE_RX_N7527PCIE_RX_P7527PCIE_TX_N75 27PCIE_TX_N64 27PCIE_TX_P64 27PCIE_RX_P6427PCIE_RX_N6427PCIE_RX_P8028PCIE_TX_N80 28PCIE_TX_P80 28PCIE_RX_N8028PCIE_RX_P8128PCIE_TX_P81 28PCIE_TX_N81 28PCIE_RX_N8128PCIE_RX_P8228PCIE_RX_N8228PCIE_TX_N82 28PCIE_TX_P82 28PCIE_RX_P8328PCIE_RX_N8328PCIE_TX_P83 28PCIE_TX_N83 28PCIE_RX_P8428PCIE_RX_N8428PCIE_TX_N84 28PCIE_TX_P84 28PCIE_RX_P8528PCIE_RX_N8528PCIE_TX_P85 28PCIE_TX_N85 28PCIE_RX_P8628PCIE_RX_N8628PCIE_TX_P86 28PCIE_TX_N86 28PCIE_RX_P8728PCIE_RX_N8728PCIE_TX_P87 28PCIE_TX_N87 28PCIE_RX_P8828PCIE_RX_N8828PCIE_TX_P88 28PCIE_TX_N88 28PCIE_RX_P8928PCIE_RX_N8928PCIE_TX_P89 28PCIE_TX_N89 28PCIE_TX_P90 28PCIE_RX_N9028PCIE_RX_P9028PCIE_TX_N90 28PCIE_TX_P91 28PCIE_RX_P9128PCIE_RX_N9128PCIE_TX_N91 28PCIE_TX_P92 28PCIE_RX_N9228PCIE_RX_P9228PCIE_TX_N92 28PCIE_RX_P9328PCIE_TX_P93 28PCIE_TX_N93 28PCIE_RX_N9328PCIE_RX_P9428PCIE_TX_N94 28PCIE_TX_P94 28PCIE_RX_N9428PCIE_RX_P9528PCIE_TX_P95 28PCIE_TX_N95 28PCIE_RX_N9528PCIE_TX_P76 12PCIE_TX_N76 12PCIE_RX_N7612PCIE_RX_P7612PCIE_TX_P78 44PCIE_TX_N78 44PCIE_RX_N7844PCIE_RX_P7844
Title
Size Document Number R e v
Date: Sheet o f
Lightning PMC PEB -11PM8536 PCIE STACK 4-5A335 60Friday, March 31, 2017Lightning PMC PEB -1http://www.wiwynn.com8F, 90, Sec.1, Xintai 5th Rd., Xizhi Dist.,New Taipei City 22102, Taiwan (R.O.C.)
Title
Size Document Number R e v
Date: Sheet o f
Lightning PMC PEB -11PM8536 PCIE STACK 4-5A335 60Friday, March 31, 2017Lightning PMC PEB -1http://www.wiwynn.com8F, 90, Sec.1, Xintai 5th Rd., Xizhi Dist.,New Taipei City 22102, Taiwan (R.O.C.)
Title
Size Document Number R e v
Date: Sheet o f
Lightning PMC PEB -11PM8536 PCIE STACK 4-5A335 60Friday, March 31, 2017Lightning PMC PEB -1http://www.wiwynn.com8F, 90, Sec.1, Xintai 5th Rd., Xizhi Dist.,New Taipei City 22102, Taiwan (R.O.C.)
C360 SCD22U10V2KX-1GP12
 C410 SCD22U10V2KX-1GP12
C358 SCD22U10V2KX-1GP12
 C408 SCD22U10V2KX-1GP12
C356 SCD22U10V2KX-1GP12
 C396 SCD22U10V2KX-1GP12
C389 SCD22U10V2KX-1GP12
C394 SCD22U10V2KX-1GP12
C387 SCD22U10V2KX-1GP12
C392 SCD22U10V2KX-1GP12
C385 SCD22U10V2KX-1GP12
C406 SCD22U10V2KX-1GP12
C362 SCD22U10V2KX-1GP12
 C380 SCD22U10V2KX-1GP12
C398 SCD22U10V2KX-1GP12
C404 SCD22U10V2KX-1GP12
C402 SCD22U10V2KX-1GP12
C400 SCD22U10V2KX-1GP12
6 OF 13
PM8546A-FEIP-GP
U1FRX80_NAN26RX80_PAM26RX81_NAP27RX81_PAN27RX82_NAN28RX82_PAM28RX83_NAP29RX83_PAN29RX84_NAN30RX84_PAM30RX85_NAP31RX85_PAN31RX86_NAN32RX86_PAM32RX87_NAP33RX87_PAN33RX88_NAH36RX88_PAH35RX89_NAG37RX89_PAG36RX90_NAF36RX90_PAF35RX91_NAE37RX91_PAE36RX92_NAD36RX92_PAD35RX93_NAC37RX93_PAC36RX94_NAB36RX94_PAB35RX95_NAA37RX95_PAA36TX80_NAT26TX80_PAR26TX81_NAU27TX81_PAT27TX82_NAT28TX82_PAR28TX83_NAU29TX83_PAT29TX84_NAT30TX84_PAR30TX85_NAU31TX85_PAT31TX86_NAT32TX86_PAR32TX87_NAU33TX87_PAT33TX88_NAU36TX88_PAU35TX89_NAT37TX89_PAT36TX90_NAR36TX90_PAR35TX91_NAP37TX91_PAP36TX92_NAN36TX92_PAN35TX93_NAM37TX93_PAM36TX94_NAL36TX94_PAL35TX95_NAK37TX95_PAK36
C641 SCD22U10V2KX-1GP
NOPOP
12
 C391 SCD22U10V2KX-1GP12
C383 SCD22U10V2KX-1GP12
C411 SCD22U10V2KX-1GP12
C409 SCD22U10V2KX-1GP12
C639 SCD22U10V2KX-1GPNOPOP12
 C405 SCD22U10V2KX-1GP12
C403 SCD22U10V2KX-1GP12
C401 SCD22U10V2KX-1GP12
C397 SCD22U10V2KX-1GP12
C395 SCD22U10V2KX-1GP12
C393 SCD22U10V2KX-1GP12
C353 SCD22U10V2KX-1GP12
C378 SCD22U10V2KX-1GP12
 C381 SCD22U10V2KX-1GP12
C407 SCD22U10V2KX-1GP12
C351 SCD22U10V2KX-1GP12
C349 SCD22U10V2KX-1GP12
C347 SCD22U10V2KX-1GP12
C345 SCD22U10V2KX-1GP12
 C399 SCD22U10V2KX-1GP12
C379 SCD22U10V2KX-1GP12
C355 SCD22U10V2KX-1GP12
C352 SCD22U10V2KX-1GP12
C350 SCD22U10V2KX-1GP12
C348 SCD22U10V2KX-1GP12
C359 SCD22U10V2KX-1GP12
C357 SCD22U10V2KX-1GP12
C361 SCD22U10V2KX-1GP12
C367 SCD22U10V2KX-1GP12
C365 SCD22U10V2KX-1GP12
C346 SCD22U10V2KX-1GP12
C363 SCD22U10V2KX-1GP12
C354 SCD22U10V2KX-1GP12
5 OF 13
PM8546A-FEIP-GP
U1ERX64_NAN8RX64_PAM8RX65_NAP9RX65_PAN9RX66_NAN10RX66_PAM10RX67_NAP11RX67_PAN11RX68_NAN12RX68_PAM12RX69_NAP13RX69_PAN13RX70_NAN14RX70_PAM14RX71_NAP15RX71_PAN15RX72_NAN17RX72_PAM17RX73_NAP18RX73_PAN18RX74_NAN19RX74_PAM19RX75_NAP20RX75_PAN20RX76_NAN21RX76_PAM21RX77_NAP22RX77_PAN22RX78_NAN23RX78_PAM23RX79_NAP24RX79_PAN24TX64_NAT8TX64_PAR8TX65_NAU9TX65_PAT9TX66_NAT10TX66_PAR10TX67_NAU11TX67_PAT11TX68_NAT12TX68_PAR12TX69_NAU13TX69_PAT13TX70_NAT14TX70_PAR14TX71_NAU15TX71_PAT15TX72_NAT17TX72_PAR17TX73_NAU18TX73_PAT18TX74_NAT19TX74_PAR19TX75_NAU20TX75_PAT20TX76_NAT21TX76_PAR21TX77_NAU22TX77_PAT22TX78_NAT23TX78_PAR23TX79_NAU24TX79_PAT24
C390 SCD22U10V2KX-1GP12
C388 SCD22U10V2KX-1GP12
C386 SCD22U10V2KX-1GP12
C384 SCD22U10V2KX-1GP12
C382 SCD22U10V2KX-1GP12
C368 SCD22U10V2KX-1GP12
C366 SCD22U10V2KX-1GP12
C364 SCD22U10V2KX-1GP12



5
5
4
4
3
3
2
2
1
1
D D
C C
B B
A A
LVDS 1.8V
DEFAULT：1、2  pin  (disable) Address=0x30
AVS_ENB_RTHERM_EMITTHERM_BASEVSS_572VSS_571BOOT_RECOVERY#_RBOOT_RECOVERY#BOOT_RECOVERY_0BOOT_RECOVERY_1THERM_EMIT_RTHERM_BASE_RTHERM_EMITTHERM_BASEMAX6654_ADD0MAX6654_ADD1I2C_MAX6654_CLKI2C_MAX6654_DATMAX6654_ALERT#DUT_VDDODUT_VDDO
P3V3_STBY
PCIE_REFCLK_D_N31PCIE_REFCLK_D_P31PM8536_RST#32 PCIE_REFCLK_S1_N 27PCIE_REFCLK_S1_P 27PCIE_REFCLK_S2_P 27PCIE_REFCLK_S2_N 27PCIE_REFCLK_S3_N 27PCIE_REFCLK_S3_P 27PCIE_REFCLK_S4_P 27PCIE_REFCLK_S4_N 27PCIE_REFCLK_S5_P 12PCIE_REFCLK_S5_N 12PCIE_REFCLK_H0_N29PCIE_REFCLK_H0_P29PCIE_REFCLK_H1_N29PCIE_REFCLK_H1_P29PCIE_REFCLK_H2_N28PCIE_REFCLK_H2_P28PCIE_REFCLK_H3_N28PCIE_REFCLK_H3_P28 BMC_I2C5_D_PEB_SDA11,21,23,31,46BMC_I2C5_D_PEB_SCL11,21,23,31,46AVS_ENB 52,53
Title
Size Document Number Re v
Date: Sheet o f
Lightning PMC PEB -11PM8536 CLOCK & RESETCustom36 60Friday, March 31, 2017Lightning PMC PEB -1http://www.wiwynn.com8F, 90, Sec.1, Xintai 5th Rd., Xizhi Dist.,New Taipei City 22102, Taiwan (R.O.C.)
Title
Size Document Number Re v
Date: Sheet o f
Lightning PMC PEB -11PM8536 CLOCK & RESETCustom36 60Friday, March 31, 2017Lightning PMC PEB -1http://www.wiwynn.com8F, 90, Sec.1, Xintai 5th Rd., Xizhi Dist.,New Taipei City 22102, Taiwan (R.O.C.)
Title
Size Document Number Re v
Date: Sheet o f
Lightning PMC PEB -11PM8536 CLOCK & RESETCustom36 60Friday, March 31, 2017Lightning PMC PEB -1http://www.wiwynn.com8F, 90, Sec.1, Xintai 5th Rd., Xizhi Dist.,New Taipei City 22102, Taiwan (R.O.C.)
R314K7R2F-GP
NOPOP
12
R533R1J-GPNOPOP
12
R29100KR2F-L1-GP
NOPOP
12
R833R1J-GPNOPOP
12 TP2341
R270R2J-2-GP12
R584K7R2F-GP12
 R4 0R2J-2-GP12
C42SCD1U10V2KX-5GP12
7 OF 13
PM8546A-FEIP-GPU1GPCIE_REFCLK_D_RXI_NY30PCIE_REFCLK_D_RXI_PY29PCIE_REFCLK_H0_RXI_NW30PCIE_REFCLK_H0_RXI_PW29PCIE_REFCLK_H1_RXI_NAB30PCIE_REFCLK_H1_RXI_PAB29PCIE_REFCLK_H2_RXI_NAA30PCIE_REFCLK_H2_RXI_PAA29PCIE_REFCLK_H3_RXI_NAC30PCIE_REFCLK_H3_RXI_PAC29RST#AG32PCIE_RESET#AH33VSS_571AH31VSS_572P27PCIE_REFCLK_S0_TXO_NW33PCIE_REFCLK_S0_TXO_PW32PCIE_REFCLK_S1_TXO_NY33PCIE_REFCLK_S1_TXO_PY32PCIE_REFCLK_S2_TXO_NAB33PCIE_REFCLK_S2_TXO_PAB32PCIE_REFCLK_S3_TXO_NAA33PCIE_REFCLK_S3_TXO_PAA32PCIE_REFCLK_S4_TXO_NAC33PCIE_REFCLK_S4_TXO_PAC32PCIE_REFCLK_S5_TXO_NAD33PCIE_REFCLK_S5_TXO_PAD32AVS_EN#H31THERM_BASEJ29THERM_EMITJ30NC#H32H32NC#H33H33NC#H27H27NC#H28H28NC#H29H29NC#H30H30NC#AH28AH28
U4MAX6654MEE-2-GPNC#11VCC2DXP3DXN4NC#55ADD16GND7GND8NC#1616STBY#15SMBCLK14NC#1313SMBDATA12ALERT#11ADD010NC#99
R633R1J-GPNOPOP
12
R933R1J-GPNOPOP
12
R3601 1KR2F-3-GP12
R12 0R2J-2-GP12
R1 0R2J-2-GP12
R360310KR2F-2-GP12
R2690R2J-2-GP12
R304K7R2F-GP
NOPOP
12
R6310KR2F-2-GP12
JP10PIN-CON3-S-GP123
R3 0R2J-2-GP12
 R2700R2J-2-GP12
R280R2J-2-GP12
R733R1J-GPNOPOP
12
R3602 1KR2F-3-GP12
R254K7R2F-GP12



5
5
4
4
3
3
2
2
1
1
D D
C C
B B
A A
To BMC RGMII(The Interface Operation Voltage is different with BMC; PM8536:1.8V, BMC: 3.3V)
EJTAG Header
to buf --> BMC
to GPIO EXP
1.8V
PMC UART LEVEL SHIFT
to EEPROM
3.3V
ADD=0100111(0x4E)
PVT 20161110
LBI_BYTEN#LBI_ADDR_3_RLBI_OE#LBI_ADDR_4_RBOOTSTRAP_R_1LBI_WE#LBI_ADDR_5_RBOOTSTRAP_R_2BOOTSTRAP_R_3MDIOLBI_DATA_9LBI_DATA_8LBI_ADDR_6_RBOOTSTRAP_R_5BOOTSTRAP_R_4LBI_ADDR_7_RLBI_DATA11_RLBI_ADDR_10BOOTSTRAP_R_7BOOTSTRAP_R_6LBI_DATA13_RLBI_DATA12_RLBI_ADDR_9RMII_TXD_0BOOTSTRAP_R_9BOOTSTRAP_R_8GPIO108_RGPIO109_RGPIO107_RLBI_ADDR_8LBI_DATA14_RBOOTSTRAP_R_10LBI_ADDR_0_RRMII_TXD_1RMII_TX_ENLBI_ADDR_1_RLBI_ADDR_12_RLBI_ADDR_2_RTWI_SCL5
DUT_TDOEJTAG_TDI
TWI_SDA5TWI_SDA9RS232_URTSB0RS232_UCTSB0
EJTAG_PWREJTAG_TDODUT_TAP_SEL_RTWI_SRST#6TWI_SCL10TWI_SRST#2DUT_TAP_SELTWI_SCL6TWI_SDA10EJTAG_RSTBEJTAG_TCK
TWI_SDA6TWI_SRST#7TWI_SRST#3EJTAG_TCK_REJTAG_TCKEJTAG_DINTDUT_TDO_RDUT_TDODUT_TDI_RDUT_TDIEJTAG_TMS_REJTAG_TMSEJTAG_TRSTB_REJTAG_TRSTBEJTAG_RSTB
TWI_SRST#4TWI_SRST#8
EJTAG_TRSTBEJTAG_TMSDUT_TDI
TWI_SCL4SPI_CSB0_1TWI_SDA4TWI_SRST#5UART_USOUTUART_USINTWI_SRST#9TWI_SRST#1
BOOTSTRAP_R_0BOOTSTRAP_R_1BOOTSTRAP_R_2BOOTSTRAP_R_3BOOTSTRAP_R_4BOOTSTRAP_R_5BOOTSTRAP_R_6BOOTSTRAP_R_7BOOTSTRAP_R_8BOOTSTRAP_R_9BOOTSTRAP_R_10BOOTSTRAP0BOOTSTRAP1BOOTSTRAP3BOOTSTRAP5BOOTSTRAP7BOOTSTRAP9BOOTSTRAP10
BOOTSTRAP_R_0LBI_DATA_0LBI_DATA_1LBI_DATA_2LBI_DATA_3LBI_DATA_4LBI_DATA_5LBI_DATA_6LBI_DATA_7LBI_DATA15LBI_CE#0LBI_CE#2LBI_CE#3RMII_REF_CLKRMII_RXD_0RMII_RXD_1RMII_CRS_DVRMII_RX_ERMDCLINKTWI_SCL3TWI_SDA3IOEXP_PMC1_INT#UART_USINEXP_SMART_RX_RSAS_SMART_R_TXSAS_SMART_R_RXUART_USOUTEXP_SMART_TX_RSMART_UART_ENTPINMDIOBOOTSTRAP6BOOTSTRAP4BOOTSTRAP8BOOTSTRAP2IOEXP_PMC1_AD2IOEXP_PMC1_AD0IOEXP_PMC1_AD1IOEXP_PMC1_AD2IOEXP_PMC1_AD0IOEXP_PMC1_AD1IOEXP_TWI_SCL3IOEXP_TWI_SDA3IOEXP_PMC1_AD0IOEXP_PMC1_AD1TWI_SCL3IOEXP_PMC1_AD2IOEXP_PMC1_INT#TWI_SDA3
TWI_SRST#0HOST5_RST_N_LSHOST2_RST_N_LSHOST8_RST_N_LSHOST6_RST_N_LSHOST7_RST_N_LSHOST1_RST_N_LSHOST3_RST_N_LSHOST5_RST_N_LSHOST2_RST_N_LSHOST8_RST_N_LSHOST6_RST_N_LSHOST7_RST_N_LSHOST1_RST_N_LSHOST3_RST_N_LSHOST4_RST_N_LSHOST4_RST_N_LS
UPLINK4PM8536_HBUPLINK1VS4_LEDUPLINK3UPLINK8VS2_LEDUPLINK6PEWAKE#VS6_LEDVS1_LEDUPLINK5VS3_LEDUPLINK2UPLINK7VS5_LEDLBI_DATA10MAX7311_TP301IOEXP_PEWAKE#PM8536_HBDUT_VDDODUT_VDDO
P3V3_GPIO
DUT_VDDOP3V3_STBYP1V8_STBYDUT_VDDO
P3V3_STBY
P3V3_STBY
DUT_VDDO
P3V3_STBY
P3V3_GPIODUT_VDDOTWI_SCL1 41TWI_SDA1 41TWI_SDA2 42TWI_SCL2 42SPI_DATA0_0 42SPI_CLK0 42SPI_CSB0_0 42TWI_SCL0 21TWI_SDA0 21SPI_DATA0_3 42SPI_DATA0_2 42SPI_DATA0_1 42EXP_SMART_RX 13,25EXP_SMART_TX 13,25HOST8_RST_N_LS32HOST1_RST_N_LS32HOST2_RST_N_LS32HOST3_RST_N_LS32HOST4_RST_N_LS32HOST5_RST_N_LS32HOST6_RST_N_LS32HOST7_RST_N_LS32 IOEXP_INT#_1 41IOEXP_INT#_2 41IOEXP_INT#_3 41IOEXP_INT#_4 41VS5_LED 22VS6_LED 22UPLINK1 22UPLINK2 22UPLINK3 22UPLINK4 22UPLINK5 22UPLINK6 22UPLINK7 22UPLINK8 22VS1_LED 22VS2_LED 22VS3_LED 22VS4_LED 22PEWAKE# 12PM8536_HB 24
Title
Size Document Number Re v
Date: Sheet o f
Lightning PMC PEB -11PM8536 I2C & LBICustom37 60Friday, March 31, 2017Lightning PMC PEB -1http://www.wiwynn.com8F, 90, Sec.1, Xintai 5th Rd., Xizhi Dist.,New Taipei City 22102, Taiwan (R.O.C.)
Title
Size Document Number Re v
Date: Sheet o f
Lightning PMC PEB -11PM8536 I2C & LBICustom37 60Friday, March 31, 2017Lightning PMC PEB -1http://www.wiwynn.com8F, 90, Sec.1, Xintai 5th Rd., Xizhi Dist.,New Taipei City 22102, Taiwan (R.O.C.)
Title
Size Document Number Re v
Date: Sheet o f
Lightning PMC PEB -11PM8536 I2C & LBICustom37 60Friday, March 31, 2017Lightning PMC PEB -1http://www.wiwynn.com8F, 90, Sec.1, Xintai 5th Rd., Xizhi Dist.,New Taipei City 22102, Taiwan (R.O.C.)
TP2991TP1901
R814 4K7R2F-GP12
TP2851
R3722 4K7R2F-GP12
R816 4K7R2F-GP12
R3702 4K7R2F-GPNOPOP12
TP2091
R7792KR2F-3-GP12
R4172 4K7R2F-GP12
TP2871
R792 4K7R2F-GP12
R818 4K7R2F-GP12 TP3001
R789 4K7R2F-GP12
TP2801
R52710KR2F-2-GPNOPOP12
R755150R2F-1-GP12
R754 33D2R2F-GP12
R787 4K7R2F-GP12
R820 4K7R2F-GPNOPOP12
TP2881
R3721 4K7R2F-GP12
R830 0R2J-2-GP12
R4173 4K7R2F-GP12
R785 4K7R2F-GP12
R7424K7R2F-GP12
SR842 10KR2F-2-GP12TP1921
 R7914 330R2J-3-GP12
R813 4K7R2F-GPNOPOP12 TP2841TP2381
R7641KR2F-3-GP12
R825 0R2J-2-GP12
R783 4K7R2F-GP12
R815 4K7R2F-GPNOPOP12
 R7731KR2F-3-GP12
R3703 4K7R2F-GPNOPOP12
R781 4K7R2F-GP12
R817 4K7R2F-GPNOPOP12
R7474K7R2F-GP12TP2621 TP2811
R4174 4K7R2F-GP12TP2391
R762 0R2J-2-GP12
 SR947 0R2J-2-GP12
R819 4K7R2F-GPNOPOP12
 R73015KR2F-GP12
 R55910KR2F-2-GP12TP2651
R758 0R2J-2-GP12
R821 4K7R2F-GP12TP2631
CN5MLX-CONN14A-16-GP1357911132468101214NP1NP2
R4175 4K7R2F-GP12
R3704 4K7R2F-GPNOPOP12
R79900R2J-2-GP12
TP1221 TP2941
R4158 4K7R2F-GP12TP3011TP2781
R7763K3R2F-2-GP12
R827 0R2J-2-GP12TP2081 TP2831
U187TXS0102DCUR-1-GPB21GND2VCCA3A24A15OE6VCCB7B18
R4176 4K7R2F-GP12TP3111TP1211TP2741TP2771TP2671TP3091TP2681TP2111
C3701SCD1U25V2KX-2-GP12
R4159 4K7R2F-GP12
R7674K7R2F-GP12
R3705 4K7R2F-GPNOPOP12
R832 0R2J-2-GP12
 SR948 0R2J-2-GP12
R756 0R2J-2-GP12
TP2221TP1201
R4177 4K7R2F-GP12
R7723K3R2F-2-GP12
R3724 4K7R2F-GP12
R780 4K7R2F-GP12
 R4164 4K7R2F-GP12
R56810KR2F-2-GP12
R8394K7R2F-GP12
R822 4K7R2F-GPNOPOP12TP3041
R7714K7R2F-GP12
SC1302SCD1U16V2KX-3GP12TP2821
R829 0R2J-2-GP12TP1991
 R4178 4K7R2F-GP12
R3707 4K7R2F-GPNOPOP12
R3723 4K7R2F-GP12
R4166 4K7R2F-GP12
R790 4K7R2F-GP12
 R59310KR2F-2-GP12TP2011
R788 4K7R2F-GP12TP2131 TP2891
 SR949 0R2J-2-GP12TP1981TP2071TP2001
R786 4K7R2F-GP12
 R7998 330R2J-3-GP12TP2101TP1241TP2021TP2641
R7753K3R2F-2-GP12
R3717 4K7R2F-GP12
R784 4K7R2F-GP12
 R4167 4K7R2F-GP12
R794 4K7R2F-GP12
R7444K7R2F-GP12TP2141 TP2901
R7704K7R2F-GP12TP1941
R761 0R2J-2-GP12
SC1303SCD1U16V2KX-3GP12
R7661KR2F-3-GP12
R796 4K7R2F-GPNOPOP12
R782 4K7R2F-GP12
R749 0R2J-2-GP12
R3708 4K7R2F-GPNOPOP12TP2031TP1971TP2151
R798 4K7R2F-GPNOPOP12
TP2911
R4168 4K7R2F-GP12
R808 4K7R2F-GP12
TP2791
SR950 0R2J-2-GP12
U203MAX7311AUG-GPINT#1I/O04I/O15I/O26I/O37I/O48I/O59I/O610I/O711GND12SCL22SDA23V+24I/O813I/O914I/O1015I/O1116I/O1217I/O1318I/O1419I/O1520AD021AD12AD23
R826 0R2J-2-GP12
R3718 4K7R2F-GP12
R810 4K7R2F-GP12 TP3101
R793 4K7R2F-GPNOPOP12
R7101KR2F-3-GP12TP1961
 R7684K7R2F-GP12
 R4169 4K7R2F-GP12
R795 4K7R2F-GPNOPOP12
R7454K7R2F-GP12
R3706 4K7R2F-GPNOPOP12
8 OF 13
PM8546A-FEIP-GP
U1HLBI_ADDR_0AB28LBI_ADDR_1AB27LBI_ADDR_2AC31LBI_ADDR_3AC28LBI_ADDR_4AC27LBI_ADDR_5AD31LBI_ADDR_6AD30LBI_ADDR_7AD29LBI_ADDR_8AD27LBI_ADDR_9AE33LBI_ADDR_10AE31LBI_ADDR_11AE30LBI_ADDR_12AE28LBI_ADDR_13V34LBI_ADDR_14W35LBI_ADDR_15W34LBI_ADDR_16W37LBI_ADDR_17Y34LBI_ADDR_18W36LBI_ADDR_19W27LBI_ADDR_20W31LBI_ADDR_21Y28LBI_ADDR_22Y27LBI_ADDR_23AA27LBI_BYTEN#U30LBI_OE#U32LBI_WE#V27LBI_DATA_0R33LBI_DATA_1T30LBI_DATA_2T31LBI_DATA_3T33LBI_DATA_4T32LBI_DATA_5U28LBI_DATA_6U29LBI_DATA_7U27LBI_DATA_8AK27LBI_DATA_9AK28LBI_DATA_10AK29LBI_DATA_11AK30LBI_DATA_12AK31LBI_DATA_13AK32LBI_DATA_14AK33LBI_DATA_15V30LBI_CE_0#V31LBI_CE_1#V29LBI_CE_2#V33LBI_CE_3#U33RMII_TXD_0AF33RMII_TXD_1AF32RMII_TX_ENAE27RMII_REF_CLKAF28RMII_RXD_0AF30RMII_RXD_1AF29RMII_CRS_DVAF27RMII_RX_ERAF31MDCAH30MDIOAH27LINKAH26TWI_SRST_0#J33TWI_SCL_0J31TWI_SDA_0J32TWI_SRST_1#K31TWI_SCL_1K27TWI_SDA_1K30TWI_SRST_2#L28TWI_SCL_2K28TWI_SDA_2K33TWI_SRST_3#P30TWI_SCL_3P29TWI_SDA_3P32TWI_SRST_4#P33TWI_SCL_4R27TWI_SDA_4R28TWI_SRST_5#M26TWI_SCL_5L30TWI_SDA_5L29TWI_SRST_6#M32TWI_SCL_6M27TWI_SDA_6M31TWI_SRST_7#N30TWI_SCL_7N28TWI_SDA_7N31TWI_SRST_8#M30TWI_SCL_8L33TWI_SDA_8M28TWI_SRST_9#N27TWI_SCL_9M29TWI_SDA_9M33TWI_SCL_10N32TWI_SDA_10N33UART_USOUTR31UART_USINR32UART_UCTS#T27UART_URTS#T28QSPI_CLKAJ31QSPI_CS_0#AJ27QSPI_DATA_0AJ29QSPI_DATA_1AJ30QSPI_DATA_2AJ32QSPI_DATA_3AJ33GPIO_107L26TPOUTR30TAP_SELAG30TCKAF26TDOAG33TDIAG26TMSAG27TRST#AG28QSPI_CS_1#AJ28GPIO_108L27GPIO_109L32EJ_RST#AG29TPINR29TP3281
R797 4K7R2F-GP12
R831 0R2J-2-GP12 TP3031
R3720 4K7R2F-GP12
R7694K7R2F-GP12
R807 4K7R2F-GP12TP2041TP1641TP2061TP1931
R809 4K7R2F-GPNOPOP12
 R4170 4K7R2F-GP12
R757 0R2J-2-GP12TP2971
R3701 4K7R2F-GPNOPOP12
R7772KR2F-3-GP12
R52610KR2F-2-GPNOPOP12
R811 4K7R2F-GPNOPOP12
R828 0R2J-2-GP12
R3719 4K7R2F-GP12TP2051
R759 0R2J-2-GP12TP1351
R7603K3R2F-2-GP12
R4171 4K7R2F-GP12
R7414K7R2F-GP12
R812 4K7R2F-GP12
 R51310KR2F-2-GPNOPOP12
C3702SCD047U25V2KX-GP12TP2861



5
5
4
4
3
3
2
2
1
1
D D
C C
B B
A A
VSS_573DUT_VDDDUT_VDDO_REFDUT_VDDO
Title
Size Document Number Rev
Date: Sheet o f
Lightning PMC PEB -11PM8536 VDD VDDO AVD_PCIECustom38 60Friday, March 31, 2017Lightning PMC PEB -1http://www.wiwynn.com8F, 90, Sec.1, Xintai 5th Rd., Xizhi Dist.,New Taipei City 22102, Taiwan (R.O.C.)
Title
Size Document Number Rev
Date: Sheet o f
Lightning PMC PEB -11PM8536 VDD VDDO AVD_PCIECustom38 60Friday, March 31, 2017Lightning PMC PEB -1http://www.wiwynn.com8F, 90, Sec.1, Xintai 5th Rd., Xizhi Dist.,New Taipei City 22102, Taiwan (R.O.C.)
Title
Size Document Number Rev
Date: Sheet o f
Lightning PMC PEB -11PM8536 VDD VDDO AVD_PCIECustom38 60Friday, March 31, 2017Lightning PMC PEB -1http://www.wiwynn.com8F, 90, Sec.1, Xintai 5th Rd., Xizhi Dist.,New Taipei City 22102, Taiwan (R.O.C.)
C434SCD1U16V1KX-1-GP12
 C466SCD1U16V1KX-1-GP12
R420R2J-2-GP12
C468SCD1U16V1KX-1-GP12
C428SCD1U16V1KX-1-GP12
C446SCD1U16V1KX-1-GP12
C425SC10U16V5KX-1-GP12
C453SCD1U16V1KX-1-GP12
 C34SCD1U16V1KX-1-GP12
C437SCD1U16V1KX-1-GP12
 C467SCD1U16V1KX-1-GP12
C476SCD1U16V1KX-1-GP12
C44SCD1U16V1KX-1-GP12
C426SC10U16V5KX-1-GP12
C443SCD1U16V1KX-1-GP12
C451SCD1U16V1KX-1-GP12
 C35SCD1U16V1KX-1-GP12
C471SCD1U16V1KX-1-GP12
C435SCD1U16V1KX-1-GP12
C458SC10U16V5KX-1-GP12
C427SC10U16V5KX-1-GP12
 C37SCD1U16V1KX-1-GP12
 C485SCD1U16V1KX-1-GP12
C486SCD1U16V1KX-1-GP12
C445SCD1U16V1KX-1-GP12
C447SCD1U16V1KX-1-GP12
 C31SCD1U16V1KX-1-GP12
 C465SC47U4V5MX-2-GP12
C438SCD1U16V1KX-1-GP12
C475SCD1U16V1KX-1-GP12
C630SC10U16V5KX-1-GP12
C484SCD1U16V1KX-1-GP12
C444SCD1U16V1KX-1-GP12
C487SCD1U16V1KX-1-GP12
L1IND-10UH-147-GP-U12
C472SCD1U16V1KX-1-GP12
C436SCD1U16V1KX-1-GP12
C431SC10U16V5KX-1-GP12
C479SCD1U16V1KX-1-GP12
C470SC4D7U16V5KX-1-GP12
C441SCD1U16V1KX-1-GP12
C439SC10U16V5KX-1-GP12
C432SCD1U16V1KX-1-GP12
C469SCD1U16V1KX-1-GP12
C483SCD1U16V1KX-1-GP12
C477SC4D7U16V5KX-1-GP12
C474SCD1U16V1KX-1-GP12
C27SCD1U16V1KX-1-GP12
C480SCD1U16V1KX-1-GP12
C463SC4D7U16V5KX-1-GP12
C28SCD1U16V1KX-1-GP12
C473SCD1U16V1KX-1-GP12
C464SC4D7U16V5KX-1-GP12
C478SCD1U16V1KX-1-GP12
C457SCD1U16V1KX-1-GP12
10 OF 13
PM8546A-FEIP-GP
U1JVSS_101J11VSS_102J12VSS_103J13VSS_104J14VSS_105J15VSS_106J16VSS_107J17VSS_108J18VSS_109J19VSS_110J21VSS_111J22VSS_112J23VSS_113J24VSS_114J26VSS_115J34VSS_116J35VSS_117J36VSS_118J37VSS_119K1VSS_120K2VSS_121K3VSS_122K4VSS_123K5VSS_124K6VSS_125K8VSS_126K9VSS_127K10VSS_128K11VSS_129K12VSS_130K13VSS_131K14VSS_132K15VSS_133K16VSS_134K17VSS_135K18VSS_136K19VSS_137K20VSS_138K21VSS_139K22VSS_140K23VSS_141K24VSS_142K25VSS_143K29VSS_144K32VSS_145K34VSS_146L3VSS_147L6VSS_148L8VSS_149L9VDDO_1V8_1L31VDDO_1V8_2L34VDDO_1V8_3N34VDDO_1V8_4P28VDDO_1V8_5R26VDDO_1V8_6R34VDDO_1V8_7U26VDDO_1V8_8U31VDDO_1V8_9U34VDDO_1V8_10AA26VDDO_1V8_11AC34VDDO_1V8_12AD28VDDO_1V8_13AE34VDDO_1V8_14AG31VDDO_1V8_15AG34VDDO_1V8_16AJ34VDDO_1V8_REF_1V28VDDO_1V8_REF_2W26VDDO_1V8_REF_3AA31VSS_150L10VSS_151L11VSS_152L12VSS_153L14VSS_154L15VSS_155L16VSS_156L17VSS_157L18VSS_158L19VSS_159L21VSS_160L23VSS_161L24VSS_162L25VSS_163L35VSS_164M4VSS_165M8VSS_166M9VSS_167M10VSS_168M11VSS_169M12VSS_170M14VDDO_1V8_REF_4AA34VDDA_DTM_ESDN26VSS_573J28
C482SCD1U16V1KX-1-GP12
R411KR3F-GP12
9 OF 13
PM8546A-FEIP-GP
U1IVSS_1A2VSS_2A3VSS_3A4VSS_4A5VSS_5A6VSS_6A7VSS_7A16VSS_8A25VSS_9A34VSS_10B3VSS_11B6VSS_12B7VSS_13B16VSS_14B25VSS_15B34VSS_16B35VSS_17C4VSS_18C7VSS_19C9VSS_20C11VSS_21C13VSS_22C15VSS_23C16VSS_24C18VSS_25C20VSS_26C22VSS_27C24VSS_28C25VSS_29C27VSS_30C29VSS_31C31VSS_32C33VSS_33C34VSS_34D3VSS_35D6VSS_36D7VSS_37D8VSS_38D10VSS_39D12VSS_40D14VSS_41D16VSS_42D17VSS_43D19VSS_44D21VSS_45D23VSS_46D25VSS_47D26VSS_48D28VSS_49D30VSS_50D32VSS_51D34VSS_52D35VSS_53E4VSS_54E7VSS_55E16VSS_56E25VSS_57E34VSS_58F3VSS_59F6VSS_60F9VSS_61F11VSS_62F13VSS_63F15VSS_64F18VSS_65F20VSS_66F22VSS_67F24VSS_68F27VSS_69F29VSS_70F31VSS_71F34VSS_72F35VSS_73G4VSS_74G15VSS_75G34VSS_76H3VSS_77H6VSS_78H8VSS_79H9VSS_80H10VSS_81H11VSS_82H12VSS_83H13VSS_84H14VSS_85H15VSS_86H16VSS_87H17VSS_88H18VSS_89H19VSS_90H21VSS_91H22VSS_92H23VSS_93H24VSS_94H26VSS_95H34VSS_96H35VSS_97J4VSS_98J8VSS_99J9VSS_100J10
VDD_0V9_1M15VDD_0V9_2M17VDD_0V9_3M19VDD_0V9_4M23VDD_0V9_5M25VDD_0V9_6N14VDD_0V9_7N16VDD_0V9_8N18VDD_0V9_9N20VDD_0V9_10N22VDD_0V9_11N24VDD_0V9_12P13VDD_0V9_13P15VDD_0V9_14P17VDD_0V9_15P19VDD_0V9_16P21VDD_0V9_17P23VDD_0V9_18P25VDD_0V9_19R14VDD_0V9_20R16VDD_0V9_21R18VDD_0V9_22R20VDD_0V9_23R22VDD_0V9_24R24VDD_0V9_25T13VDD_0V9_26T15VDD_0V9_27T17VDD_0V9_28T19VDD_0V9_29T21VDD_0V9_30T23VDD_0V9_31T25VDD_0V9_32U14VDD_0V9_33U16VDD_0V9_34U18VDD_0V9_35U20VDD_0V9_36U22VDD_0V9_37U24VDD_0V9_38V13VDD_0V9_39V15VDD_0V9_40V17VDD_0V9_41V19VDD_0V9_42V21VDD_0V9_43V23VDD_0V9_44W14VDD_0V9_45W16VDD_0V9_46W18VDD_0V9_47W22VDD_0V9_48W24VDD_0V9_49Y13VDD_0V9_50Y15VDD_0V9_51Y17VDD_0V9_52Y19VDD_0V9_53Y21VDD_0V9_54Y23VDD_0V9_55Y25VDD_0V9_56AA14VDD_0V9_57AA16VDD_0V9_58AA18VDD_0V9_59AA20VDD_0V9_60AA22VDD_0V9_61AA24VDD_0V9_62AB13VDD_0V9_63AB15VDD_0V9_64AB17VDD_0V9_65AB19VDD_0V9_66AB21VDD_0V9_67AB23VDD_0V9_68AB25VDD_0V9_69AC14VDD_0V9_70AC16VDD_0V9_71AC18VDD_0V9_72AC20VDD_0V9_73AC22VDD_0V9_74AC24VDD_0V9_75AD13VDD_0V9_76AD15VDD_0V9_77AD17VDD_0V9_78AD19VDD_0V9_79AD21NC#K26K26NC#J27J27VDD_0V9_80AD23VDD_0V9_81AD25VDD_0V9_82AE14VDD_0V9_83AE16VDD_0V9_84AE18VDD_0V9_85AE20VDD_0V9_86AE22VDD_0V9_87AE24VDD_0V9_88AE26VDD_0V9_89AF15VDD_0V9_90AF17VDD_0V9_91AF19VDD_0V9_92AF23VDD_0V9_93AF25VDD_0V9_94W20
C38SCD1U16V1KX-1-GP12
C448SCD1U16V1KX-1-GP12
C481SCD1U16V1KX-1-GP12
C30SCD1U16V1KX-1-GP12
C462SCD1U16V1KX-1-GP12
C460SCD1U16V1KX-1-GP12
C39SCD1U16V1KX-1-GP12
C449SCD1U16V1KX-1-GP12
 C32SCD1U16V1KX-1-GP12
C455SC100U4V5MX-1-GP12
C454SC100U4V5MX-1-GP12
 C461SCD1U16V1KX-1-GP12
C40SCD1U16V1KX-1-GP12
C440SCD1U16V1KX-1-GP12
C452SCD1U16V1KX-1-GP12
 C33SCD1U16V1KX-1-GP12
C433SCD1U16V1KX-1-GP12
C456SC100U4V5MX-1-GP12
C459SC100U4V5MX-1-GP12
 C29SCD1U16V1KX-1-GP12
C429SCD1U16V1KX-1-GP12
C442SCD1U16V1KX-1-GP12
C450SCD1U16V1KX-1-GP12
C424SC10U16V5KX-1-GP12
 C36SCD1U16V1KX-1-GP12



5
5
4
4
3
3
2
2
1
1
D D
C C
B B
A A
DUT_AVD_PCIEDUT_AVD_PCIE_QDUT_AVD_PCIEDUT_AVD_TXDUT_AVD_PCIEDUT_AVD_PCIE
Title
Size Document Number R ev
Date: Sheet o f
Lightning PMC PEB -11PM8536 AVD_PCIECustom39 60Friday, March 31, 2017Lightning PMC PEB -1http://www.wiwynn.com8F, 90, Sec.1, Xintai 5th Rd., Xizhi Dist.,New Taipei City 22102, Taiwan (R.O.C.)
Title
Size Document Number R ev
Date: Sheet o f
Lightning PMC PEB -11PM8536 AVD_PCIECustom39 60Friday, March 31, 2017Lightning PMC PEB -1http://www.wiwynn.com8F, 90, Sec.1, Xintai 5th Rd., Xizhi Dist.,New Taipei City 22102, Taiwan (R.O.C.)
Title
Size Document Number R ev
Date: Sheet o f
Lightning PMC PEB -11PM8536 AVD_PCIECustom39 60Friday, March 31, 2017Lightning PMC PEB -1http://www.wiwynn.com8F, 90, Sec.1, Xintai 5th Rd., Xizhi Dist.,New Taipei City 22102, Taiwan (R.O.C.)
C613SCD1U16V1KX-1-GP12
C530SCD1U16V1KX-1-GP12
C537SCD1U16V1KX-1-GP12
C569SCD1U16V1KX-1-GP12
C500SCD1U16V1KX-1-GP12
C601SCD1U16V1KX-1-GP12
C550SCD1U16V1KX-1-GP12
C575SCD1U16V1KX-1-GP12
 C587SCD1U16V1KX-1-GP12
 C583SC4D7U16V5KX-1-GP12
C535SCD1U16V1KX-1-GP12
C571SCD1U16V1KX-1-GP12
C528SCD1U16V1KX-1-GP12
C501SCD1U16V1KX-1-GP12
C600SCD1U16V1KX-1-GP12
C545SCD1U16V1KX-1-GP12
C540SC4D7U16V5KX-1-GP12
C573SCD1U16V1KX-1-GP12
C564SC4D7U16V5KX-1-GP12
11 OF 13
PM8546A-FEIP-GP
U1KVSS_171M16VSS_172M18VSS_173M20VSS_174M22VSS_175M24VSS_176M34VSS_177N3VSS_178N6VSS_179N8VSS_180N9VSS_181N10VSS_182N11VSS_183N12VSS_184N13VSS_185N15VSS_186N17VSS_187N19VSS_188N21VSS_189N23VSS_190N25VSS_191N29VSS_192N35VSS_193P4VSS_194P7VSS_195P9VSS_196P11VSS_197P12VSS_198P14VSS_199P16VSS_200P18VSS_201P20VSS_202P22VSS_203P24VSS_204P26VSS_205P31VSS_206P34VSS_207R3VSS_208R6VSS_209R8VSS_210R10VSS_211R12VSS_212R13VSS_213R15VSS_214R17VSS_215R19VSS_216R21VSS_217R23VSS_218R25VSS_219R35VSS_220T4VSS_221T7VSS_222T9VSS_223T11VSS_224T12VSS_225T14VSS_226T16VSS_227T18VSS_228T20VSS_229T22VSS_230T24VSS_231T26VSS_232T29VSS_233T34VSS_234U3VSS_235U6VSS_236U8VSS_237U10AVD_PCIE_TX_1P8AVD_PCIE_TX_2P10AVD_PCIE_TX_3R7AVD_PCIE_TX_4R9AVD_PCIE_TX_5R11AVD_PCIE_TX_6T8AVD_PCIE_TX_7T10AVD_PCIE_TX_8U7AVD_PCIE_TX_9U9AVD_PCIE_TX_10U11AVD_PCIE_TX_11V8AVD_PCIE_TX_12V10AVD_PCIE_TX_13W7AVD_PCIE_TX_14W9AVD_PCIE_TX_15W11AVD_PCIE_TX_16Y8AVD_PCIE_TX_17Y10AVD_PCIE_TX_18AA7AVD_PCIE_TX_19AA9AVD_PCIE_TX_20AA11AVD_PCIE_TX_21AB8AVD_PCIE_TX_22AB10AVD_PCIE_TX_23AC7AVD_PCIE_Q_1L13AVD_PCIE_Q_2L20AVD_PCIE_Q_3V25AVD_PCIE_Q_4AG13AVD_PCIE_82M13AVD_PCIE_83M21AVD_PCIE_84AF13AVD_PCIE_85AF21AVD_PCIE_86AC26VSS_238U12VSS_239U13VSS_240U15VSS_241U17VSS_242U19VSS_243U21VSS_244U23VSS_245U25VSS_246U35VSS_247V4VSS_248V7VSS_249V9VSS_250V11VSS_251V12AVD_PCIE_Q_5AG20AVD_PCIE_TX_24AC9AVD_PCIE_TX_25AC11AVD_PCIE_TX_26AD8AVD_PCIE_TX_27AD10
C588SCD1U16V1KX-1-GP12
C529SCD1U16V1KX-1-GP12
C507SC4D7U16V5KX-1-GP12
R431KR3F-GP12
 C586SC4D7U16V5KX-1-GP12
C536SCD1U16V1KX-1-GP12
C568SCD1U16V1KX-1-GP12
C502SCD1U16V1KX-1-GP12
 C558SC4D7U16V5KX-1-GP12
C495SC100U4V5MX-1-GP12
C606SCD1U16V1KX-1-GP12
C542SCD1U16V1KX-1-GP12
L2IND-10UH-103-GP12
C513SCD1U16V1KX-1-GP12
C574SCD1U16V1KX-1-GP12
C493SCD1U16V1KX-1-GP12
C591SCD1U16V1KX-1-GP12
C556SCD1U16V1KX-1-GP12
C567SCD1U16V1KX-1-GP12
C503SCD1U16V1KX-1-GP12
C605SCD1U16V1KX-1-GP12
C543SCD1U16V1KX-1-GP12
C514SCD1U16V1KX-1-GP12
C611SCD1U16V1KX-1-GP12
C581SCD1U16V1KX-1-GP12
C525SCD1U16V1KX-1-GP12
 C584SC4D7U16V5KX-1-GP12
C491SCD1U16V1KX-1-GP12
C589SCD1U16V1KX-1-GP12
C557SCD1U16V1KX-1-GP12
C504SCD1U16V1KX-1-GP12
 C532SC4D7U16V5KX-1-GP12
C572SC4D7U16V5KX-1-GP12
C541SCD1U16V1KX-1-GP12
C509SCD1U16V1KX-1-GP12
C580SCD1U16V1KX-1-GP12
C614SCD1U16V1KX-1-GP12
C524SCD1U16V1KX-1-GP12
C518SC47U4V5MX-2-GP12
C489SCD1U16V1KX-1-GP12
C590SCD1U16V1KX-1-GP12
C555SCD1U16V1KX-1-GP12
C547SCD1U16V1KX-1-GP12
C508SCD1U16V1KX-1-GP12
 C559SC4D7U16V5KX-1-GP12
C610SCD1U16V1KX-1-GP12
C577SCD1U16V1KX-1-GP12
C520SCD1U16V1KX-1-GP12
C492SCD1U16V1KX-1-GP12
C596SCD1U16V1KX-1-GP12
C551SCD1U16V1KX-1-GP12
C497SCD1U16V1KX-1-GP12
C510SCD1U16V1KX-1-GP12
C579SCD1U16V1KX-1-GP12
C565SCD1U16V1KX-1-GP12
C607SCD1U16V1KX-1-GP12
C519SCD1U16V1KX-1-GP12
C490SCD1U16V1KX-1-GP12
C595SCD1U16V1KX-1-GP12
C603SCD1U16V1KX-1-GP12
C548SCD1U16V1KX-1-GP12
C560SC4D7U16V5KX-1-GP12
C512SCD1U16V1KX-1-GP12
C488SCD1U16V1KX-1-GP12
C570SCD1U16V1KX-1-GP12
C494SC100U4V5MX-1-GP12
C609SCD1U16V1KX-1-GP12
C516SC4D7U16V5KX-1-GP12
C522SCD1U16V1KX-1-GP12
 C618SC4D7U16V5KX-1-GP12
C594SCD1U16V1KX-1-GP12
C604SCD1U16V1KX-1-GP12
C546SCD1U16V1KX-1-GP12
C515SCD1U16V1KX-1-GP12
C511SCD1U16V1KX-1-GP12
C612SCD1U16V1KX-1-GP12
C517SC4D7U16V5KX-1-GP12
C539SCD1U16V1KX-1-GP12
C566SCD1U16V1KX-1-GP12
C617SC4D7U16V5KX-1-GP12
C523SCD1U16V1KX-1-GP12
C599SCD1U16V1KX-1-GP12
C619SC4D7U16V5KX-1-GP12
C499SCD1U16V1KX-1-GP12
C562SCD1U16V1KX-1-GP12
C608SCD1U16V1KX-1-GP12
C531SCD1U16V1KX-1-GP12
C538SCD1U16V1KX-1-GP12
C521SCD1U16V1KX-1-GP12
 C552SC4D7U16V5KX-1-GP12
C597SCD1U16V1KX-1-GP12
C554SC4D7U16V5KX-1-GP12
C576SCD1U16V1KX-1-GP12
C498SCD1U16V1KX-1-GP12
C615SCD1U16V1KX-1-GP12
C526SCD1U16V1KX-1-GP12
C534SCD1U16V1KX-1-GP12
C563SCD1U16V1KX-1-GP12
 C505SCD1U16V1KX-1-GP12
 C585SC4D7U16V5KX-1-GP12
C602SCD1U16V1KX-1-GP12
12 OF 13
PM8546A-FEIP-GP
U1LVSS_252V14VSS_253V16VSS_254V18VSS_255V20VSS_256V22VSS_257V24VSS_258V26VSS_259V32VSS_260V35VSS_261V36VSS_262V37VSS_263W1VSS_264W2VSS_265W3VSS_266W4VSS_267W5VSS_268W6VSS_269W8VSS_270W10VSS_271W12VSS_272W13VSS_273W15VSS_274W17VSS_275W19VSS_276W21VSS_277W23VSS_278W25VSS_279W28VSS_280Y4VSS_281Y7VSS_282Y9VSS_283Y11VSS_284Y12VSS_285Y14VSS_286Y16VSS_287Y18VSS_288Y20VSS_289Y22VSS_290Y24VSS_291Y26VSS_292Y31VSS_293Y35VSS_294Y36VSS_295Y37VSS_296AA3VSS_297AA6VSS_298AA8VSS_299AA10VSS_300AA12VSS_301AA13VSS_302AA15VSS_303AA17VSS_304AA19VSS_305AA21VSS_306AA23VSS_307AA25VSS_308AA28VSS_309AA35VSS_310AB4VSS_311AB7VSS_312AB9VSS_313AB11VSS_314AB12VSS_315AB14VSS_316AB16VSS_317AB18VSS_318AB20VSS_319AB22VSS_320AB24VSS_321AB26VSS_322AB31VSS_323AB34VSS_324AC3VSS_325AC6VSS_326AC8
AVD_PCIE_1F16AVD_PCIE_2F25AVD_PCIE_3F33AVD_PCIE_4G16AVD_PCIE_5G17AVD_PCIE_6G18AVD_PCIE_7G19AVD_PCIE_8G20AVD_PCIE_9G21AVD_PCIE_10G22AVD_PCIE_11G23AVD_PCIE_12G24AVD_PCIE_13G25AVD_PCIE_14G26AVD_PCIE_15G27AVD_PCIE_16G28AVD_PCIE_17G29AVD_PCIE_18G30AVD_PCIE_19G31AVD_PCIE_20G32AVD_PCIE_21G33AVD_PCIE_22H20AVD_PCIE_23H25AVD_PCIE_24J20AVD_PCIE_25J25AVD_PCIE_26AJ20AVD_PCIE_27AJ25AVD_PCIE_28AK20AVD_PCIE_29AK25AVD_PCIE_30AL16AVD_PCIE_31AL17AVD_PCIE_32AL18AVD_PCIE_33AL19AVD_PCIE_34AL20AVD_PCIE_35AL21AVD_PCIE_36AL22AVD_PCIE_37AL23AVD_PCIE_38AL24AVD_PCIE_39AL25AVD_PCIE_40AL26AVD_PCIE_41AL27AVD_PCIE_42AL28AVD_PCIE_52F7AVD_PCIE_53G7AVD_PCIE_54G8AVD_PCIE_55G9AVD_PCIE_56G10AVD_PCIE_57G11AVD_PCIE_58G12AVD_PCIE_59G13AVD_PCIE_60G14AVD_PCIE_61H7AVD_PCIE_62J7AVD_PCIE_63K7AVD_PCIE_64L7AVD_PCIE_65M7AVD_PCIE_66N7AVD_PCIE_67AE7AVD_PCIE_68AF7AVD_PCIE_69AG7AVD_PCIE_70AH7AVD_PCIE_71AJ7AVD_PCIE_72AK7AVD_PCIE_73AL7AVD_PCIE_74AL8AVD_PCIE_75AL9AVD_PCIE_76AL10AVD_PCIE_77AL11AVD_PCIE_78AL12AVD_PCIE_79AL13AVD_PCIE_80AL14AVD_PCIE_81AM7VSS_336AC35VSS_337AD4VSS_338AD7VSS_339AD9VSS_340AD11VSS_341AD12VSS_342AD14VSS_343AD16VSS_344AD18VSS_345AD20VSS_327AC10VSS_328AC12VSS_329AC13VSS_330AC15VSS_331AC17VSS_332AC19VSS_333AC21VSS_334AC23VSS_335AC25VSS_346AD22VSS_347AD24VSS_348AD26VSS_349AD34VSS_350AE3AVD_PCIE_43AL29AVD_PCIE_44AL30AVD_PCIE_45AL31AVD_PCIE_46AL32AVD_PCIE_47AL33AVD_PCIE_48AM16AVD_PCIE_49AM25AVD_PCIE_50AM33AVD_PCIE_51L22
C582SCD1U16V1KX-1-GP12
 C592SCD1U16V1KX-1-GP12
C533SCD1U16V1KX-1-GP12
C561SCD1U16V1KX-1-GP12
C616SCD1U16V1KX-1-GP12
C527SCD1U16V1KX-1-GP12
C506SCD1U16V1KX-1-GP12
 C553SC4D7U16V5KX-1-GP12
C598SCD1U16V1KX-1-GP12
C544SCD1U16V1KX-1-GP12
C549SC4D7U16V5KX-1-GP12
C496SC4D7U16V5KX-1-GP12
C578SCD1U16V1KX-1-GP12
 C593SCD1U16V1KX-1-GP12



5
5
4
4
3
3
2
2
1
1
D D
C C
B B
A A
Title
Size Document Number R e v
Date: Sheet o f
Lightning PMC PEB -11PM8536 VSSA340 60Friday, March 31, 2017Lightning PMC PEB -1http://www.wiwynn.com8F, 90, Sec.1, Xintai 5th Rd., Xizhi Dist.,New Taipei City 22102, Taiwan (R.O.C.)
Title
Size Document Number R e v
Date: Sheet o f
Lightning PMC PEB -11PM8536 VSSA340 60Friday, March 31, 2017Lightning PMC PEB -1http://www.wiwynn.com8F, 90, Sec.1, Xintai 5th Rd., Xizhi Dist.,New Taipei City 22102, Taiwan (R.O.C.)
Title
Size Document Number R e v
Date: Sheet o f
Lightning PMC PEB -11PM8536 VSSA340 60Friday, March 31, 2017Lightning PMC PEB -1http://www.wiwynn.com8F, 90, Sec.1, Xintai 5th Rd., Xizhi Dist.,New Taipei City 22102, Taiwan (R.O.C.)
13 OF 13U1M
PM8546A-FEIP-GP
VSS_351AE6VSS_352AE8VSS_353AE9VSS_354AE10VSS_355AE11VSS_356AE12VSS_357AE13VSS_358AE15VSS_359AE17VSS_360AE19VSS_361AE21VSS_362AE23VSS_363AE25VSS_364AE29VSS_365AE32VSS_366AE35VSS_367AF4VSS_368AF8VSS_369AF9VSS_370AF10VSS_371AF11VSS_372AF12VSS_373AF14VSS_374AF16VSS_375AF18VSS_376AF20VSS_377AF22VSS_378AF24VSS_379AF34VSS_380AG3VSS_381AG6VSS_382AG8VSS_383AG9VSS_384AG10VSS_385AG11VSS_386AG12VSS_387AG14VSS_388AG15VSS_389AG16VSS_390AG17VSS_391AG18VSS_392AG19VSS_393AG21VSS_394AG22VSS_395AG23VSS_396AG24VSS_397AG25VSS_398AG35VSS_399AH1VSS_400AH2VSS_401AH3VSS_402AH4VSS_403AH5VSS_404AH6VSS_405AH8VSS_406AH9VSS_407AH10VSS_408AH11VSS_409AH12VSS_410AH13VSS_411AH14VSS_412AH15VSS_413AH16VSS_414AH17VSS_415AH18VSS_416AH19VSS_417AH20VSS_418AH21VSS_419AH22VSS_420AH23VSS_421AH24VSS_422AH25VSS_423AH29VSS_424AH32VSS_425AH34VSS_426AJ4VSS_427AJ8VSS_428AJ9VSS_429AJ10VSS_430AJ11VSS_431AJ12VSS_432AJ13VSS_433AJ14VSS_434AJ15VSS_435AJ16VSS_436AJ17VSS_437AJ18VSS_438AJ19VSS_439AJ21VSS_440AJ22VSS_441AJ23VSS_442AJ24VSS_443AJ26VSS_444AJ35VSS_445AJ36VSS_446AJ37
VSS_458AK17VSS_459AK18VSS_460AK19VSS_461AK21VSS_462AK22VSS_463AK23VSS_464AK24VSS_465AK26VSS_466AK34VSS_467AK35VSS_468AL4VSS_469AL15VSS_470AL34VSS_471AM3VSS_472AM6VSS_473AM9VSS_474AM11VSS_475AM13VSS_476AM15VSS_477AM18VSS_478AM20VSS_479AM22VSS_480AM24VSS_481AM27VSS_482AM29VSS_483AM31VSS_484AM34VSS_485AM35VSS_486AN4VSS_487AN7VSS_488AN16VSS_489AN25VSS_490AN34VSS_491AP3VSS_492AP6VSS_493AP7VSS_494AP8VSS_495AP10VSS_496AP12VSS_497AP14VSS_498AP16VSS_499AP17VSS_500AP19VSS_501AP21VSS_502AP23VSS_503AP25VSS_504AP26VSS_505AP28VSS_506AP30VSS_507AP32VSS_508AP34VSS_509AP35VSS_510AR4VSS_511AR7VSS_512AR9VSS_513AR11VSS_514AR13VSS_515AR15VSS_516AR16VSS_517AR18VSS_518AR20VSS_519AR22VSS_520AR24VSS_521AR25VSS_522AR27VSS_523AR29VSS_524AR31VSS_525AR33VSS_526AR34VSS_527AT3VSS_528AT6VSS_529AT7VSS_530AT16VSS_531AT25VSS_532AT34VSS_533AT35VSS_534AU2VSS_535AU3VSS_536AU4VSS_537AU5VSS_538AU6VSS_539AU7VSS_540AU16VSS_541AU25VSS_542AU34
VSS_457AK16VSS_450AK9VSS_451AK10VSS_452AK11VSS_453AK12VSS_454AK13VSS_455AK14VSS_456AK15VSS_448AK6VSS_449AK8VSS_447AK3



5
5
4
4
3
3
2
2
1
1
D D
C C
B B
A A
from MiniSAS HD 1
from MiniSAS HD 1
from MiniSAS HD 1
ADD=0100111(0x4E)
ADD=0100000(0x40)
ADD=0100110(0x4C)
ADD=0100001(0x42)
from MiniSAS HD 1
I2C_GPIO_SCL_1I2C_GPIO_SDA_1IOEXP1_AD0IOEXP1_AD1IOEXP1_AD2IOEXP1_AD2IOEXP1_AD0IOEXP1_AD1IOEXP1_AD2IOEXP1_AD0IOEXP1_AD1IOEXP2_AD2IOEXP2_AD0IOEXP2_AD1IOEXP2_AD2IOEXP2_AD0IOEXP2_AD1I2C_GPIO_SCL_2I2C_GPIO_SDA_2IOEXP2_AD0IOEXP2_AD1IOEXP2_AD2IOEXP3_AD2IOEXP3_AD0IOEXP3_AD1IOEXP3_AD2IOEXP3_AD0IOEXP3_AD1I2C_GPIO_SCL_3I2C_GPIO_SDA_3IOEXP3_AD0IOEXP3_AD1IOEXP3_AD2IOEXP4_AD2IOEXP4_AD0IOEXP4_AD1IOEXP4_AD2IOEXP4_AD0IOEXP4_AD1I2C_GPIO_SCL_4I2C_GPIO_SDA_4IOEXP4_AD0IOEXP4_AD1IOEXP4_AD2SSD_PERST#0SSD_PWREN11SSD_PRSNT#0SSD_PERST#10SSD_PWREN0SSD_PERST#5SSD_ATNLED#10SSD_ATNLED#5SSD_PERST#11SSD_ATNLED#11SSD_PRSNT#10SSD_PRSNT#5SSD_PWREN10SSD_ATNLED#0SSD_PWREN5SSD_PRSNT#11SSD_PRSNT#6SSD_PWREN1SSD_PERST#6SSD_PWREN7SSD_PWREN2SSD_ATNLED#1SSD_ATNLED#7SSD_PERST#1SSD_PRSNT#7SSD_PERST#7SSD_PWREN6SSD_PERST#2SSD_PRSNT#1SSD_ATNLED#6SSD_ATNLED#2SSD_PRSNT#2SSD_PERST#3SSD_PRSNT#12SSD_PERST#13SSD_PWREN12SSD_PRSNT#3SSD_PRSNT#13SSD_PERST#8SSD_ATNLED#8SSD_PWREN13SSD_PRSNT#8SSD_PWREN3SSD_PERST#12SSD_ATNLED#12SSD_ATNLED#3SSD_PWREN8SSD_ATNLED#13IOEXP4_GPIO12BMC_PERST#15IOEXP4_GPIO13SSD_PERST#4SSD_ATNLED#14SSD_PRSNT#4SSD_PWREN9SSD_PERST#14SSD_PRSNT#14SSD_PWREN4SSD_ATNLED#9SSD_PERST#9SSD_PWREN14SSD_ATNLED#4SSD_PRSNT#9SSD_PERST#0SSD_PRSNT#0SSD_PERST#10SSD_PERST#5SSD_ATNLED#10SSD_ATNLED#5SSD_PERST#11SSD_ATNLED#11SSD_PRSNT#10SSD_PRSNT#5SSD_ATNLED#0SSD_PRSNT#11SSD_PRSNT#6SSD_PERST#6SSD_ATNLED#1SSD_ATNLED#7SSD_PERST#1SSD_PRSNT#7SSD_PERST#7SSD_PERST#2SSD_PRSNT#1SSD_ATNLED#6SSD_ATNLED#2SSD_PRSNT#2SSD_PERST#3SSD_PRSNT#12SSD_PERST#13SSD_PRSNT#3SSD_PRSNT#13SSD_PERST#8SSD_ATNLED#8SSD_PRSNT#8SSD_PERST#12SSD_ATNLED#12SSD_ATNLED#3SSD_ATNLED#13BMC_PERST#15SSD_PERST#4SSD_ATNLED#14SSD_PRSNT#4SSD_PERST#14SSD_PRSNT#14SSD_ATNLED#9SSD_PERST#9SSD_ATNLED#4SSD_PRSNT#9IOEXP4_GPIO14SSD_PERST#0SSD_PERST#1SSD_PERST#2SSD_PERST#3SSD_PERST#4SSD_PERST#5SSD_PERST#6SSD_PERST#7SSD_PERST#8SSD_PERST#9SSD_PERST#10SSD_PERST#11SSD_PERST#12SSD_PERST#13SSD_PERST#14
P3V3_STBY
P3V3_STBY
P3V3_STBY
P3V3_STBY
P3V3_STBY
P3V3_STBY
P3V3_STBY
P3V3_STBY
P3V3_STBY P3V3_STBY P3V3_STBY P3V3_STBY
TWI_SDA137,41TWI_SCL137,41IOEXP_INT#_137TWI_SDA137,41TWI_SCL137,41IOEXP_INT#_237TWI_SDA137,41TWI_SCL137,41IOEXP_INT#_337TWI_SDA137,41TWI_SCL137,41IOEXP_INT#_437SSD_PERST#0_R 27,32SSD_PWREN11_R 27,41SSD_PRSNT#0_R 27SSD_PERST#10_R 27,32SSD_PWREN0_R 27,41SSD_PERST#5_R 27,32SSD_ATNLED#10_R 27SSD_ATNLED#5_R 27SSD_PERST#11_R 27,32SSD_ATNLED#11_R 27SSD_PRSNT#10_R 27SSD_PRSNT#5_R 27SSD_PWREN10_R 27,41SSD_ATNLED#0_R 27SSD_PWREN5_R 27,41SSD_PRSNT#11_R 27SSD_PRSNT#6_R 27SSD_PWREN1_R 27,41SSD_PERST#6_R 27,32SSD_PWREN7_R 27,41SSD_PWREN2_R 27,41SSD_ATNLED#1_R 27SSD_ATNLED#7_R 27SSD_PERST#1_R 27,32SSD_PRSNT#7_R 27SSD_PERST#7_R 27,32SSD_PWREN6_R 27,41SSD_PERST#2_R 27,32SSD_PRSNT#1_R 27SSD_ATNLED#6_R 27SSD_ATNLED#2_R 27SSD_PRSNT#2_R 27SSD_PERST#3_R 27,32SSD_PRSNT#12_R 27SSD_PERST#13_R 27,32SSD_PRSNT#3_R 27SSD_PWREN12_R 27,41SSD_PRSNT#13_R 27SSD_PERST#8_R 27,32SSD_ATNLED#8_R 27SSD_PWREN13_R 27,41SSD_PRSNT#8_R 27SSD_PWREN3_R 27,41SSD_PERST#12_R 27,32SSD_ATNLED#12_R 27SSD_ATNLED#3_R 27SSD_PWREN8_R 27,41SSD_ATNLED#13_R 27BMC_PERST#_R 12,44SSD_PERST#4_R 27,32SSD_ATNLED#14_R 27SSD_PRSNT#4_R 27SSD_PWREN9_R 27,41SSD_PERST#14_R 27,32SSD_PRSNT#14_R 27SSD_PWREN4_R 27,41SSD_ATNLED#9_R 27SSD_PERST#9_R 27,32SSD_PWREN14_R 27,41SSD_ATNLED#4_R 27SSD_PRSNT#9_R 27SSD_PERST#9 32SSD_PERST#5 32SSD_PERST#10 32SSD_PERST#1 32SSD_PERST#6 32SSD_PERST#13 32SSD_PERST#11 32SSD_PERST#2 32SSD_PERST#7 32SSD_PERST#14 32SSD_PERST#12 32SSD_PERST#3 32SSD_PERST#8 32SSD_PERST#4 32SSD_PERST#0 32SSD_PWREN1_R 27,41SSD_PWREN7_R 27,41SSD_PWREN2_R 27,41SSD_PWREN6_R 27,41SSD_PWREN9_R 27,41SSD_PWREN4_R 27,41SSD_PWREN14_R 27,41SSD_PWREN11_R 27,41SSD_PWREN0_R 27,41SSD_PWREN10_R 27,41SSD_PWREN5_R 27,41SSD_PWREN12_R 27,41SSD_PWREN13_R 27,41SSD_PWREN3_R 27,41SSD_PWREN8_R 27,41
Title
Size Document Number R ev
Date: Sheet o f
Lightning PMC PEB -11GPIO EXPANDERCustom41 60Friday, March 31, 2017Lightning PMC PEB -1http://www.wiwynn.com8F, 90, Sec.1, Xintai 5th Rd., Xizhi Dist.,New Taipei City 22102, Taiwan (R.O.C.)
Title
Size Document Number R ev
Date: Sheet o f
Lightning PMC PEB -11GPIO EXPANDERCustom41 60Friday, March 31, 2017Lightning PMC PEB -1http://www.wiwynn.com8F, 90, Sec.1, Xintai 5th Rd., Xizhi Dist.,New Taipei City 22102, Taiwan (R.O.C.)
Title
Size Document Number R ev
Date: Sheet o f
Lightning PMC PEB -11GPIO EXPANDERCustom41 60Friday, March 31, 2017Lightning PMC PEB -1http://www.wiwynn.com8F, 90, Sec.1, Xintai 5th Rd., Xizhi Dist.,New Taipei City 22102, Taiwan (R.O.C.)
R55110KR2F-2-GPNOPOP12
R55310KR2F-2-GP12
R79450R2J-2-GP12
R4155 4K7R2F-GPNOPOP12
R79530R2J-2-GP12
R79200R2J-2-GP12
R79650R2J-2-GP12
R4114 4K7R2F-GPNOPOP12
R79160R2J-2-GP12
R79310R2J-2-GP12
R79680R2J-2-GPNOPOP12
 R79460R2J-2-GP12
C415SCD1U25V2KX-2-GP12
 C4160 SCD1U25V3KX-GP12
R79520R2J-2-GP12
R4133 4K7R2F-GPNOPOP12
R4115 4K7R2F-GP12
R57310KR2F-2-GP12
R4149 4K7R2F-GPNOPOP12
C4108 SCD1U25V3KX-GP12
R79400R2J-2-GP12
 R79340R2J-2-GP12
R9035 4K7R2F-GP12
R79660R2J-2-GP12
U201MAX7311AUG-GPINT#1I/O04I/O15I/O26I/O37I/O48I/O59I/O610I/O711GND12SCL22SDA23V+24I/O813I/O914I/O1015I/O1116I/O1217I/O1318I/O1419I/O1520AD021AD12AD23
R79390R2J-2-GP12
R4118 4K7R2F-GP12
R4134 4K7R2F-GP12
R79120R2J-2-GP12
R4165 4K7R2F-GPNOPOP12
R79330R2J-2-GP12
R79710R2J-2-GPNOPOP12
 R9043 4K7R2F-GP12
R4156 4K7R2F-GP12
R4150 4K7R2F-GP12
R79270R2J-2-GP12
 R79770R2J-2-GPNOPOP12
R55510KR2F-2-GP12
R9036 4K7R2F-GP12
R4116 4K7R2F-GPNOPOP12
U199MAX7311AUG-GPINT#1I/O04I/O15I/O26I/O37I/O48I/O59I/O610I/O711GND12SCL22SDA23V+24I/O813I/O914I/O1015I/O1116I/O1217I/O1318I/O1419I/O1520AD021AD12AD23
R4125 4K7R2F-GP12
R4141 4K7R2F-GP12
R79130R2J-2-GP12
R4119 4K7R2F-GPNOPOP12
R79800R2J-2-GPNOPOP12
R79240R2J-2-GP12
C4128 SCD1U25V3KX-GP12
R4135 4K7R2F-GPNOPOP12
R51610KR2F-2-GPNOPOP12
C417SCD1U25V2KX-2-GP12
R79730R2J-2-GPNOPOP12
R9029 4K7R2F-GP12
R79280R2J-2-GP12
R4151 4K7R2F-GPNOPOP12
R79440R2J-2-GP12
 R79720R2J-2-GPNOPOP12
C8092SCD047U25V2KX-GP12
R4126 4K7R2F-GPNOPOP12
 R79690R2J-2-GPNOPOP12
R9037 4K7R2F-GP12
C4132 SCD1U25V3KX-GP12
R79550R2J-2-GP12
R4120 4K7R2F-GPNOPOP12
R4136 4K7R2F-GPNOPOP12
R4142 4K7R2F-GPNOPOP12
 C8094SCD047U25V2KX-GP12
R45310KR2F-2-GPNOPOP12
 R79470R2J-2-GP12
R9030 4K7R2F-GP12
R79810R2J-2-GPNOPOP12
R79180R2J-2-GP12
 C4136 SCD1U25V3KX-GP12
R9038 4K7R2F-GP12
R79700R2J-2-GPNOPOP12
 R79320R2J-2-GP12
R79540R2J-2-GP12
R57410KR2F-2-GP12
R4127 4K7R2F-GPNOPOP12
R4143 4K7R2F-GPNOPOP12
R9031 4K7R2F-GP12
R51710KR2F-2-GPNOPOP12
R79480R2J-2-GP12
R4102 4K7R2F-GP12
 R9039 4K7R2F-GP12
R79220R2J-2-GP12
 R79420R2J-2-GP12
R4152 4K7R2F-GPNOPOP12
 C8091SCD047U25V2KX-GP12
 R79600R2J-2-GP12
R79630R2J-2-GP12
 C4124 SCD1U25V3KX-GP12
R55710KR2F-2-GP12
R79590R2J-2-GP12 TP1691
R9032 4K7R2F-GP12
R79190R2J-2-GP12
R79500R2J-2-GP12
R4128 4K7R2F-GP12
R4144 4K7R2F-GP12
R79610R2J-2-GP12
R9040 4K7R2F-GP12
U198MAX7311AUG-GPINT#1I/O04I/O15I/O26I/O37I/O48I/O59I/O610I/O711GND12SCL22SDA23V+24I/O813I/O914I/O1015I/O1116I/O1217I/O1318I/O1419I/O1520AD021AD12AD23
 R57510KR2F-2-GP12
R52510KR2F-2-GPNOPOP12
 C4112 SCD1U25V3KX-GP12
R4160 4K7R2F-GPNOPOP12
R79560R2J-2-GP12
 R79790R2J-2-GPNOPOP12
C4144 SCD1U25V3KX-GP12TP1841
R79750R2J-2-GPNOPOP12
R9033 4K7R2F-GP12
R51810KR2F-2-GP12
R4106 4K7R2F-GPNOPOP12
R4104 4K7R2F-GPNOPOP12
R79430R2J-2-GP12
R9041 4K7R2F-GP12
R4129 4K7R2F-GP12
R55010KR2F-2-GPNOPOP12
R79990R2J-2-GP12
C4104 SCD1U25V3KX-GP12
R4145 4K7R2F-GPNOPOP12
R79640R2J-2-GP12
R53610KR2F-2-GPNOPOP12
 R79360R2J-2-GP12
R4108 4K7R2F-GPNOPOP12
 C4148 SCD1U25V3KX-GP12
R9034 4K7R2F-GP12
R79370R2J-2-GP12
R4161 4K7R2F-GPNOPOP12
R79380R2J-2-GP12
 C4120 SCD1U25V3KX-GP12
R4107 4K7R2F-GP12 TP1671
R9042 4K7R2F-GP12
R79570R2J-2-GP12
U200MAX7311AUG-GPINT#1I/O04I/O15I/O26I/O37I/O48I/O59I/O610I/O711GND12SCL22SDA23V+24I/O813I/O914I/O1015I/O1116I/O1217I/O1318I/O1419I/O1520AD021AD12AD23
R79350R2J-2-GP12
R4110 4K7R2F-GPNOPOP12
R4130 4K7R2F-GPNOPOP12
R4146 4K7R2F-GP12
R4103 4K7R2F-GPNOPOP12
R53510KR2F-2-GPNOPOP12
C416SCD1U25V2KX-2-GP12
 C4152 SCD1U25V3KX-GP12
R57610KR2F-2-GPNOPOP12
R79740R2J-2-GPNOPOP12
R54710KR2F-2-GP12
C418SCD1U25V2KX-2-GP12
R79300R2J-2-GP12
C4116 SCD1U25V3KX-GP12
R79260R2J-2-GP12
R79760R2J-2-GPNOPOP12
R55210KR2F-2-GPNOPOP12
C8093SCD047U25V2KX-GP12
R4111 4K7R2F-GP12
R79290R2J-2-GP12
C4140 SCD1U25V3KX-GP12
R51910KR2F-2-GP12
 R79250R2J-2-GP12
R4122 4K7R2F-GPNOPOP12
R54910KR2F-2-GP12
R4138 4K7R2F-GPNOPOP12
R79620R2J-2-GP12
R4112 4K7R2F-GPNOPOP12
R79150R2J-2-GP12
R79580R2J-2-GP12
R79410R2J-2-GP12
 R79670R2J-2-GPNOPOP12
R4154 4K7R2F-GPNOPOP12
R57710KR2F-2-GPNOPOP12
R79490R2J-2-GP12
R79780R2J-2-GPNOPOP12
 C4156 SCD1U25V3KX-GP12
R52110KR2F-2-GP12
R4163 4K7R2F-GP12
R54810KR2F-2-GP12
 R56310KR2F-2-GPNOPOP12
R79210R2J-2-GP12
R4123 4K7R2F-GPNOPOP12
R4139 4K7R2F-GPNOPOP12
R79230R2J-2-GP12
R79510R2J-2-GP12



5
5
4
4
3
3
2
2
1
1
D D
C C
B B
A A
TWI Address=0xA0
Serial EEPROM 128kb
SPI_DATA0_1_RSPI_DATA0_2_RSPI_DATA0_3_RSPI_DATA0_0_RSPI_DATA0_3_RSPI_CLK0_RSPI_DATA0_0_REEPROM_A0EEPROM_WP_8536EEPROM_A1EEPROM_A2TWI_SDA2_RTWI_SCL2_R
SPI_CLK0_RSPI_CSB0_0SPI_DATA0_1_RSPI_DATA0_2_RP1V8_STBYP1V8_STBYDUT_VDDODUT_VDDO
P3V3_STBYP3V3_STBYP3V3_STBYSPI_CLK0 37SPI_DATA0_137SPI_DATA0_237SPI_CSB0_037 SPI_DATA0_3 37SPI_DATA0_0 37
TWI_SDA2 37TWI_SCL2 37
Title
Size Document Number R e v
Date: Sheet o f
Lightning PMC PEB -11FLASH、EEPROMA342 60Friday, March 31, 2017Lightning PMC PEB -1http://www.wiwynn.com8F, 90, Sec.1, Xintai 5th Rd., Xizhi Dist.,New Taipei City 22102, Taiwan (R.O.C.)
Title
Size Document Number R e v
Date: Sheet o f
Lightning PMC PEB -11FLASH、EEPROMA342 60Friday, March 31, 2017Lightning PMC PEB -1http://www.wiwynn.com8F, 90, Sec.1, Xintai 5th Rd., Xizhi Dist.,New Taipei City 22102, Taiwan (R.O.C.)
Title
Size Document Number R e v
Date: Sheet o f
Lightning PMC PEB -11FLASH、EEPROMA342 60Friday, March 31, 2017Lightning PMC PEB -1http://www.wiwynn.com8F, 90, Sec.1, Xintai 5th Rd., Xizhi Dist.,New Taipei City 22102, Taiwan (R.O.C.)
U10CAT24C128WI-GT3-GP
NOPOP
A01A12A23VSS4SDA5SCL6WP7VCC8
R955 33R2J-2-GP12
R9520R2J-2-GP
NOPOP
12
R653100KR2F-L1-GP
NOPOP
12
R9530R2J-2-GPNOPOP12
R662100KR2F-L1-GP
NOPOP
12
R654100KR2F-L1-GP
NOPOP
12
SKT4SKT-SPI8P-9-GP12345678
R661100KR2F-L1-GP
NOPOP
12
R657100KR2F-L1-GP
NOPOP
12
R651100KR2F-L1-GP
NOPOP
12
C727SCD1U10V2KX-5GP
NOPOP
12
R447100KR2F-L1-GP12
R957 33R2J-2-GP12
R615100KR2F-L1-GP
NOPOP
12
R660100KR2F-L1-GP
NOPOP
12
C723SC10U16V5KX-1-GP12
R650100KR2F-L1-GP
NOPOP
12
R959 33R2J-2-GP12
R958 82R2F-4-GP12
R956 33R2J-2-GP12
U9N25Q128A11ESE40F-GPS#1DQ12W#/VPP/DQ23VSS4DQ05C6RESET#/HOLD#/DQ37VCC8
R663100KR2F-L1-GP
NOPOP
12
R616100KR2F-L1-GP12
R652100KR2F-L1-GP
NOPOP
12
C728SCD01U25V2KX-3GP
NOPOP
12
R458100KR2F-L1-GP
NOPOP
12
C724SCD1U10V2KX-5GP12



5
5
4
4
3
3
2
2
1
1
D D
C C
B B
A A
IPMB_DATIPMB_CLKIPMB_DATIPMB_CLKCN2_P23TRAY_POWER_CRIT_NBMC_INT_NIPMB_CLKIPMB_DATP3V3_STBYP3V3_STBYP3V3_STBYP3V3_STBYP3V3_STBYMNG_RX_DP 19MNG_RX_DN19MNG_TX_DP 19MNG_TX_DN19BMC_INT_N13TRAY_ID113TRAY_ID0 13TRAY_ID2 13TRAY_POWER_CRIT_N13TRAY_RESET_N14BP_PRSNT_N 13BMC_I2C14_MINI8_SCL_S 12BMC_I2C14_MINI8_SDA_S12TRAY_MBP_CTRL_EN_N 46MBP_UART_RX 13MBP_UART_TX13
Title
Size Document Number R e v
Date: Sheet o f
Lightning PMC PEB -11MBP CONNA343 60Friday, March 31, 2017Lightning PMC PEB -1http://www.wiwynn.com8F, 90, Sec.1, Xintai 5th Rd., Xizhi Dist.,New Taipei City 22102, Taiwan (R.O.C.)
Title
Size Document Number R e v
Date: Sheet o f
Lightning PMC PEB -11MBP CONNA343 60Friday, March 31, 2017Lightning PMC PEB -1http://www.wiwynn.com8F, 90, Sec.1, Xintai 5th Rd., Xizhi Dist.,New Taipei City 22102, Taiwan (R.O.C.)
Title
Size Document Number R e v
Date: Sheet o f
Lightning PMC PEB -11MBP CONNA343 60Friday, March 31, 2017Lightning PMC PEB -1http://www.wiwynn.com8F, 90, Sec.1, Xintai 5th Rd., Xizhi Dist.,New Taipei City 22102, Taiwan (R.O.C.)
R736 0R2J-2-GPNOPOP12
R7014K7R2F-GP
NOPOP
12
CN2PIN-CONN24A-4-GP
NOPOP
135791113151719212324681012141618202224
R737 0R2J-2-GPNOPOP12
R57110KR2F-2-GP
NOPOP
12
 R7004K7R2F-GP
NOPOP
12
R739 0R2J-2-GPNOPOP12
R57010KR2F-2-GP
NOPOP
12
R5694K7R2F-GP
NOPOP
12



5
5
4
4
3
3
2
2
1
1
D D
C C
B B
A A
Synchronous clock50MHz +/- 100ppm
To BMC
4.99K 1% Place near chip
8Mb flash
NOPOP NOPOP POP
R474
POPPOPI210-AT
ConfigureR425
I210-AS
R374
NOPOP
50M_CLK_OE
I210_PERST_NPHY_RESET_N
CLK_50M_BMC0CLK_50M_RMII_PHYFM_OSC_50M_EN
CLK_50M_RMII_PHYRMII_PHY_BMC_RXD0_RRMII_PHY_BMC_RXD1_R
50M_CLK_OUT50M_CLK_OUT_RCLK_50M_BMC_NCSINCSI_10G_RCLK
CLK_50M_RMII_PHY_INNCSI_ARB_INNCSI_ARB_OUTTP_SDP0TP_SDP2TP_SDP3XTAL_OUT_I210_RXTAL_OUT_I210XTAL_IN_I210_RXTAL_IN_I210NIC_JTCKNIC_JTDINIC_JTDONIC_JTMSLAN_SE_RSETLAN_MAIN_PWR_OKNVM_CS_NNVM_SINVM_SONVM_SKLAN1_51LAN1_56I210_CTOPI210_CBOTRMII_BMC_PHY_TXD0RMII_PHY_BMC_RXD1PHY_RESET_NLAN_SMB_CLKLAN_SMB_DATRMII_BMC_TX_ENCLK_50M_RMII_PHYNIC_JTCKNIC_JTDINIC_JTDONIC_JTMSRMII_BMC_PHY_TXD1LAN_MAIN_PWR_OKFM_PCH_LAN1_DISABLE_NRMII_PHY_BMC_RXD0U44_HOLD_NNVM_SK_RU44_WP_NNVM_SO_RNVM_SI_R
PCIE_DIS
NVM_CS_N_RNVM_SO_RU44_WP_NU44_HOLD_NNVM_SK_RNVM_SI_R
I210_PERST_NPCIE_RX_CAP_P78PCIE_RX_CAP_N78PHY_WAKE_N
RMII_BMC_CRS_DVP3V3_STBYP3V3_STBYP3V3_STBYP3V3_STBYP1V5_I210P0V9_I210P0V9_I210P3V3_STBYP1V5_I210P1V5_I210P3V3_STBYP3V3_STBYP3V3_STBYP3V3_STBY
P3V3_STBY
P3V3_STBY
P3V3_STBYRMII_PHY_BMC_RXD1 13RMII_PHY_BMC_RXD0 13
CLK_50M_BMC0 13CLK_50M_BMC_NCSI 13
LAN_SMB_CLK12LAN_SMB_DAT12LAN_SMB_ALERT_N12RMII_BMC_TX_EN 13RMII_BMC_PHY_TXD0 13RMII_BMC_PHY_TXD1 13LED_MDI0_100M_N19LED_MDI0_LINK_N19LED_MDI0_1G_N19NIC0_MDI0_N3 19NIC0_MDI0_P3 19NIC0_MDI0_N2 19NIC0_MDI0_P2 19NIC0_MDI0_N1 19NIC0_MDI0_P1 19NIC0_MDI0_N0 19NIC0_MDI0_P0 19FM_PCH_LAN1_DISABLE_N14NVM_SK_R 10NVM_CS_N_R10NVM_SI_R 10NVM_SO_R10
I210_CS_N_R 10I210_SO_R 10I210_SI_R 10I210_SK_R 10FM_BMC_RESET_N13,14,26BMC_PERST#_R12,41BMC_I210_PERST_N13 PCIE_RX_N78 35PCIE_RX_P78 35PCIE_TX_P7835PCIE_TX_N7835I210_REFCLK_D_N31I210_REFCLK_D_P31RMII_BMC_CRS_DV 13
Title
Size Document Number R e v
Date: Sheet o f
Lightning PMC PEB -11INTEL I210A344 60Friday, March 31, 2017Lightning PMC PEB -1http://www.wiwynn.com8F, 90, Sec.1, Xintai 5th Rd., Xizhi Dist.,New Taipei City 22102, Taiwan (R.O.C.)
Title
Size Document Number R e v
Date: Sheet o f
Lightning PMC PEB -11INTEL I210A344 60Friday, March 31, 2017Lightning PMC PEB -1http://www.wiwynn.com8F, 90, Sec.1, Xintai 5th Rd., Xizhi Dist.,New Taipei City 22102, Taiwan (R.O.C.)
Title
Size Document Number R e v
Date: Sheet o f
Lightning PMC PEB -11INTEL I210A344 60Friday, March 31, 2017Lightning PMC PEB -1http://www.wiwynn.com8F, 90, Sec.1, Xintai 5th Rd., Xizhi Dist.,New Taipei City 22102, Taiwan (R.O.C.)
R52833R2J-2-GP
NOPOP12
 R406 3K3R2F-2-GPNOPOP12
R372 0R2J-2-GPNOPOP12 TP1651
 R392 10KR2F-2-GPNOPOP12
R4740R3J-0-U-GP
NOPOP
12TP1491
C236SC1U10V2KX-4-GP
NOPOP
12TP1631TP1571TP1581
R382 0R2J-2-GPNOPOP12
R393 10KR2F-2-GPNOPOP12
R379 33R2J-2-GPNOPOP12
R405 3K3R2F-2-GPNOPOP12
C232SC1U10V2KX-4-GP
NOPOP
12
R39910KR2F-2-GP
NOPOP
12
 R401 10KR2F-2-GPNOPOP12
R394 10KR2F-2-GPNOPOP12
R166 4K7R2F-GPNOPOP12
R398 10KR2F-2-GPNOPOP12
R375 0R2J-2-GPNOPOP12
R5013K3R2F-2-GP
NOPOP
12
 R459 10KR2F-2-GPNOPOP12
R4993K3R2F-2-GP
NOPOP
12
C233SC1U10V2KX-4-GP
NOPOP
12
 R404 3K3R2F-2-GPNOPOP12
R395 10KR2F-2-GPNOPOP12
U83SN74LVC1G08DCKR-GP
NOPOP
B2A1GND3Y4VCC5
R4250R3J-0-U-GPNOPOP12
C234SC12P50V2JN-3GP
NOPOP
12
 R383 0R2J-2-GPNOPOP12
R419 10KR2F-2-GPNOPOP12
R397 10KR2F-2-GPNOPOP12
R5083K3R2F-2-GP
NOPOP
12
2 OF 4U20BWGI210AT-2-GP
NOPOP
SDP360SDP262SDP1/PCIE_DIS61SDP063LED233LED130LED031MDI_MINUS349MDI_PLUS350MDI_MINUS252MDI_PLUS253MDI_MINUS154MDI_PLUS155MDI_MINUS057MDI_PLUS058
C377SCD039U16V2KX-GP
NOPOP
12
R3740R3J-0-U-GPNOPOP12
TP1481
C642 SCD22U10V2KX-1GP
NOPOP
12
C235SC12P50V2JN-3GP
NOPOP
12
C3216SCD1U25V2KX-2-GP
NOPOP
12
 R387 0R2J-2-GPNOPOP12
R403 3K3R2F-2-GPNOPOP12
R40010KR2F-2-GP
NOPOP12
 R556 10KR2F-2-GPNOPOP12
C643 SCD22U10V2KX-1GPNOPOP12
R376 0R2J-2-GPNOPOP12
R386 0R2J-2-GPNOPOP12
U21ICS551MLFT-GP
NOPOP
ICLK1Q12Q23Q34Q45GND6VDD7OE8
R416 0R2J-2-GPNOPOP12
X1OSC-50MHZ-8-GP-U
NOPOP
CONT1GND2OUT3VDD4
R390 4K99R2F-L-GPNOPOP12
R385 0R2J-2-GPNOPOP12
1 OF 4U20AWGI210AT-2-GP
NOPOP
PE_RP24PE_RN23PECLKP26PECLKN25PE_RST#17PE_WAKE#16SMB_CLK34SMB_DAT36SMB_ALRT#35PE_TP21PE_TN20NC_SI_CLK_IN2NC_SI_TX_EN7NC_SI_CRS_DV3NC_SI_ARB_OUT44NC_SI_ARB_IN43NC_SI_RXD15NC_SI_RXD06NC_SI_TXD18NC_SI_TXD09
X11XTAL-25MHZ-96GP
NOPOP
12
 R49733K2R2F-GP
NOPOP
12
U44W25Q80DVSSIG-1-GP
NOPOP
CS#1DO/IO12WP#/IO23GND4VCC8HOLD#/IO37CLK6DI/IO05
3 OF 4U20CWGI210AT-2-GP
NOPOP
XTAL146XTAL245LAN_PWR_GOOD1RSET48JTAG_CLK19JTAG_TDI29JTAG_TDO4JTAG_TMS18DEV_OFF#28NVM_SO14NVM_SI12NVM_CS#15NVM_SK13
TP1341
TP1521
R476 10KR2F-2-GPNOPOP12
R5003K3R2F-2-GP
NOPOP
12
R396 100KR2J-1-GPNOPOP12
R384 0R2J-2-GPNOPOP12
SKT6SKT-SPI8P-9-GP
NOPOP
12345678
R646 10KR2F-2-GPNOPOP12 TP1701
4 OF 4U20DWGI210AT-2-GP
NOPOP
VDD0P911VDD0P959VDD1P547VDD1P556VDD0P932VDD0P942VDD3P351VDD3P341VDD0P9_OUT38VDD1P5_OUT39VDD3P310VDD3P327VDD3P364GND65CTOP40CBOT37NC#2222
R49833K2R2F-GP
NOPOP
12
R402 3K3R2F-2-GPNOPOP12
TP1501



5
5
4
4
3
3
2
2
1
1
D D
C C
B B
A A
VDD3P3 DECOUPLING
VDD0P9 DECOUPLING
VDD0P9_OUT
VDD1P5 DECOUPLING
P3V3_STBYP1V5_I210P1V5_I210P0V9_I210P0V9_I210
Title
Size Document Number R e v
Date: Sheet o f
Lightning PMC PEB -11INTEL I210 DECOUPLINGA345 60Friday, March 31, 2017Lightning PMC PEB -1http://www.wiwynn.com8F, 90, Sec.1, Xintai 5th Rd., Xizhi Dist.,New Taipei City 22102, Taiwan (R.O.C.)
Title
Size Document Number R e v
Date: Sheet o f
Lightning PMC PEB -11INTEL I210 DECOUPLINGA345 60Friday, March 31, 2017Lightning PMC PEB -1http://www.wiwynn.com8F, 90, Sec.1, Xintai 5th Rd., Xizhi Dist.,New Taipei City 22102, Taiwan (R.O.C.)
Title
Size Document Number R e v
Date: Sheet o f
Lightning PMC PEB -11INTEL I210 DECOUPLINGA345 60Friday, March 31, 2017Lightning PMC PEB -1http://www.wiwynn.com8F, 90, Sec.1, Xintai 5th Rd., Xizhi Dist.,New Taipei City 22102, Taiwan (R.O.C.)
C627SC10U6D3V5KX-4GP
NOPOP
12
C633SC47U4V5MX-2-GP
NOPOP
12
C632SCD1U16V2KX-3GP
NOPOP
12
C640SC10U6D3V5KX-4GP
NOPOP
12
C631SCD1U16V2KX-3GP
NOPOP
12
C624SC10U6D3V5KX-4GP
NOPOP
12
C629SCD1U16V2KX-3GP
NOPOP
12
C634SC10U6D3V5KX-4GP
NOPOP
12
 C623SCD1U16V2KX-3GP
NOPOP
12
C622SCD1U16V2KX-3GP
NOPOP
12
C620SCD1U16V2KX-3GP
NOPOP
12
C635SCD1U16V2KX-3GP
NOPOP
12
C626SC10U6D3V5KX-4GP
NOPOP
12
C621SCD1U16V2KX-3GP
NOPOP
12
C638SCD1U16V2KX-3GP
NOPOP
12
C637SCD1U16V2KX-3GP
NOPOP
12
C625SC47U6D3V5MX-1-GP
NOPOP
12
C430SC10U6D3V5KX-4GP
NOPOP
12
C636SCD1U16V2KX-3GP
NOPOP
12
C628SCD1U16V2KX-3GP
NOPOP
12
C423SC47U4V5MX-2-GP
NOPOP
12



5
5
4
4
3
3
2
2
1
1
D D
C C
B B
A A
1.4V
I2C Address = 0x11(7-bit)
Viset = 1050mV
UV = 9.26V 
OV = 14.34V 
Vsense = 21mV
7.1A
Power rail :65 W Controller : ADM1278TDC :7.1AOCP :10.5A
Iset 10.5A
Pset 65W
Istart 5A
Itrip = 10.5A
put R2119,R2122,R2120,R2123 close to U2
L : Power offH : Power on
PVT 20161111
MB0_TEMP_CMB0_P12V_PWGIN_RMB0_TIME_R
MB0_CM_GATE_R
MB0_CM_ADR1_RMB0_TEMPMB0_P12V_PWRGOODMB0_SPISS_PDMB0_CM_SENSE_R1_PMB0_PSET_R
MB0_P12V_PWRGOOD
MB0_VCAP_RMB0_ISET_RMB0_SPISS_PD
MB0_CM_ADR2_RMB0_CM_SENSE_R1_NMB0_CM_VOUT_R
MB0_CM_GATEMB0_12V_CTRL_GATE1MB0_CM_UV_RMB0_ISTART_RMB0_CM_GATEMB0_VCAP_RMB0_P12V_RMB0_CM_ADR1_RMB0_CM_ADR2_RMB0_VCAP_R
MB0_CM_SENSE_R1_NMB0_CM_SENSE_PMB0_CM_SENSE_R1_PMB0_CM_SENSE_NMB0_P12V_PWGIN_RMB0_RETRY_RMATED_P12V_ENMB0_HS_ENABLEHSW_SCL_2HSW_SDA_2ADM1278_HS_NADM1278_HS_PMB0_TIME_RMB0_ISET_RMB0_PSET_RMB0_CM_SENSE_PMB0_CM_SENSE_NMB0_CM_VOUT_RMB0_VCCMB0_VCAP_RMB0_CM_OV_RMB0_ISTART_RMB0_CM_UV_RMB0_RETRY_RMB0_HS_ENABLEMB0_TEMP_EMB0_TEMP
MB0_CM_OV_RMB0_CM_SENSE_R1_NADM1278_HS_PMB0_CM_SENSE_R1_PADM1278_HS_NPCIe_MATED#_AQ95_GQ95_DPCIe_MATED#_BP12V_PCIEP12VMB0_P12V_MAIN_RAGND_CURRENT_MON
AGND_CURRENT_MONAGND_CURRENT_MONAGND_CURRENT_MONAGND_CURRENT_MON
AGND_CURRENT_MONAGND_CURRENT_MON
AGND_CURRENT_MON
AGND_CURRENT_MONAGND_CURRENT_MON
P12V
AGND_CURRENT_MON
AGND_CURRENT_MON
AGND_CURRENT_MONAGND_CURRENT_MONAGND_CURRENT_MONAGND_CURRENT_MON
P12V
AGND_CURRENT_MON
P12V_PCIE
P12V_PCIEAGND_CURRENT_MONAGND_CURRENT_MONP12V_PCIEP12V_PCIEP12V_PCIEPCIe_MATED#_B 27BMC_I2C5_D_PEB_SDA 11,21,23,31,36BMC_I2C5_D_PEB_SCL 11,21,23,31,36MB0_P12V_PWRGOOD 47PCIe_MATED#_A 27TRAY_MBP_CTRL_EN_N 43
Title
Size Document Number R e v
Date: Sheet o f
Lightning PMC PEB -1112V-DCIN_ADM1278 HSCCustom46 60Friday, March 31, 2017Lightning PMC PEB -1http://www.wiwynn.com8F, 90, Sec.1, Xintai 5th Rd., Xizhi Dist.,New Taipei City 22102, Taiwan (R.O.C.)
Title
Size Document Number R e v
Date: Sheet o f
Lightning PMC PEB -1112V-DCIN_ADM1278 HSCCustom46 60Friday, March 31, 2017Lightning PMC PEB -1http://www.wiwynn.com8F, 90, Sec.1, Xintai 5th Rd., Xizhi Dist.,New Taipei City 22102, Taiwan (R.O.C.)
Title
Size Document Number R e v
Date: Sheet o f
Lightning PMC PEB -1112V-DCIN_ADM1278 HSCCustom46 60Friday, March 31, 2017Lightning PMC PEB -1http://www.wiwynn.com8F, 90, Sec.1, Xintai 5th Rd., Xizhi Dist.,New Taipei City 22102, Taiwan (R.O.C.)
C7273SCD01U16V2KX-3GP12
C7272SCD1U16V2KX-3GP12
R902843K2R2F-L-GP12
R210749K9R2F-L-GP12
 Q962N7002K-1-GP
NOPOP
GDS
R209939K2R2F-L-GP12
PC1083SC1U25V3KX-GP12
R9026100R2D-GP
NOPOP12
Q942N7002K-1-GPGDS
C372SCD015U25V2KX-GP
NOPOP
12
 R9025100R2D-GP
NOPOP12
R211110R2J-2-GP12
U2ADM1278-2ACPZ-RL-1-GPVCAP2MCLK10MDAT11GPO2/ALERT2#14VOUT20GND22PGND23VCC30UV31OV32GND33ISTART4TIMER5RETRY#17MO-26MO+29HS-27HS+28GPO1/ALERT1#/CONV13PSET1ISET3ADR17ADR28SCL16SDA15GATE24TEMP25FAULT#6SPISS#9ENABLE12CSOUT19PWGIN21PWRGD18
C339SC22UF16V6KX-GP12
PR90070R2J-2-GPNOPOP12
Q952N7002K-1-GP
NOPOP
GDS
C7316SCD1U25V3JX-GP12
R210226K1R2F-2-GP12
R61727KR2F-L-GP12
C7276SC1U16V3KX-5GP12
R2122 10R2F-L-GP12
 PQ33MMBT3904FN3-GP-U
NOPOP
CBE
D
S
G
Q23PSMN0R9-25YLC-GP54123
D36MM3Z15VT1G-GP-U
NOPOP
KA
R21181MR3J-L-GP
NOPOP
12
R21096K04R2F-GP12
 R66427KR2F-L-GP
NOPOP
12
PR3910KR2F-2-GP
NOPOP
12
R21720R2J-2-GP12
R21140R2J-2-GP12
R21083K74R2F-GP12
R68810KR2J-3-GP
NOPOP
12
R9020D002RL3115F-L-GP1234
C7317SCD1U25V3JX-GP12
 P21210R0603-PAD-2-GP-U12
R2120 10R2F-L-GP12
R2123 10R2F-L-GP12
 R6921K33R3F-GP12
C7274SCD1U25V3KX-GP12
 R2103150KR2J-GP12
PR3810KR2F-2-GP12
R2117100KR2J-4-GP12
 R73810KR3F-L-GP
NOPOP
12
R2174100KR2J-4-GP12
PR90060R2J-2-GP12
R209810R2F-L-GP12
R21150R2J-2-GP
NOPOP
12
 R122611KR2F-L-GP12
R21130R2J-2-GP
NOPOP
12
C7277SC1U16V3KX-5GP12
C8099SC1KP50V2KX-1GP
NOPOP
12
 R1227100KR2F-L1-GP12
PR90040R2J-2-GP12
Q932N7002K-1-GPGDS
C419SCD015U25V2KX-GP
NOPOP
12
 PR3410KR2F-2-GP12
R6910R2J-2-GP12
R210649K9R2F-L-GP12
D37SMF15A-GPAK
R2119 10R2F-L-GP12
 R64827KR2F-L-GP12
R902322K6R2F-1-GP12
R902763K4R2F-2-GP12
 R2110 1KR2J-1-GP12
C7278SCD1U25V3JX-GP12
R2171100KR2J-4-GP12
R69010KR3F-L-GP12
C7275SC1U16V3KX-5GP12
 C7279SCD033U50V3KX-1GP12
CA1SC2D2U25V5KX-2-GP
NOPOP
12



5
5
4
4
3
3
2
2
1
1
D D
C C
B B
A A
Irate =1.6A, Isat=2A
Power rail :P5V_STBYController : SY8120(Fswitching=500KHz)TDC :1.001A (USB 2.0 STANDARD)MAX :1.001AOCP :1.5A
P5V_STBY_BSP5V_STBY_FBP5V_STBY_BS_RCP5V_STBY_LXP5V_STBY_ENP5V_STBY_LRQ46_GQ46_DQ45_DP12VP5V_STBYP5V_STBY_LR
P12V_PCIE
P5V_STBYMB0_P12V_PWRGOOD46,47MB0_P12V_PWRGOOD46,47
Title
Size Document Number R e v
Date: Sheet o f
Lightning PMC PEB -11PWRSW_P5V_STBY_SY8120A347 60Friday, March 31, 2017Lightning PMC PEB -1http://www.wiwynn.com8F, 90, Sec.1, Xintai 5th Rd., Xizhi Dist.,New Taipei City 22102, Taiwan (R.O.C.)
Title
Size Document Number R e v
Date: Sheet o f
Lightning PMC PEB -11PWRSW_P5V_STBY_SY8120A347 60Friday, March 31, 2017Lightning PMC PEB -1http://www.wiwynn.com8F, 90, Sec.1, Xintai 5th Rd., Xizhi Dist.,New Taipei City 22102, Taiwan (R.O.C.)
Title
Size Document Number R e v
Date: Sheet o f
Lightning PMC PEB -11PWRSW_P5V_STBY_SY8120A347 60Friday, March 31, 2017Lightning PMC PEB -1http://www.wiwynn.com8F, 90, Sec.1, Xintai 5th Rd., Xizhi Dist.,New Taipei City 22102, Taiwan (R.O.C.)
PL1IND-15UH-87-GP12
PG2GAP-CLOSE-PWR-3-GP12
PR630R3J-0-U-GP12
R63147KR2F-GP12
Q46DSS4240T-7-GPCBE
PR6610KR2F-2-GP
NOPOP
12
PC72SC4D7U25V5KX-1-GP12
 PC66SC22U16V5MX-4-GP12
PC71SCD1U50V3KX-GP12
R73510KR2F-2-GP12
Q452N7002K-1-GPGDS
PR90080R2J-2-GP12
PU58SY8120ABC-GPBS1GND2FB3EN4IN5LX6
PR65100KR2F-L1-GP12
PR113K3R2F-L1-GP12
PG1GAP-CLOSE-PWR-3-GP12
PC68SC22U16V5MX-4-GP12
PR6447KR2F-GP
NOPOP
12
 PC73SC22P50V3JN-GP12
R73447R6F-GP12



5
5
4
4
3
3
2
2
1
1
D D
C C
B B
A A
FCCM Mode SS=5.6ms
OCP = 11A
Power rail : P3V3_PWRController : TPS53319 (Fswitching=500KHz)TDC : 7.296AMAX : 7.296AOCP : 11A
FS=500KHz
Idc:10A  Isat:14A
P3V3_STBY_VFBP3V3_STBY_ROVPP3V3_STBY_VINP3V3_STBY_VREGP3V3_STBY_LLP3V3_STBY_ENP3V3_STBY_VREGP3V3_STBY_TRIPP3V3_STBY_VBSTP3V3_STBY_MODEP3V3_STBY_VBST_RCP3V3_STBY_VDDP3V3_STBY_SNBP3V3_STBY_VFB_RP3V3_STBY_LL_RP3V3_STBY_RFQ40_DQ3203_GQ42_DQ43_BQ43_C
P3V3_PWRP12V
AGND_P3V3_STBYAGND_P3V3_STBYAGND_P3V3_STBYAGND_P3V3_STBYP12VAGND_P3V3_STBYAGND_P3V3_STBYP3V3_STBYP3V3_PWRP3V3_PWRP3V3_STBYP3V3_STBYP3V3_STBYP3V3_STBYP3V3_GPIOP3V3_STBY
P12V_PCIE
P5V_STBYP3V3_STBY_PG48,49PWRGD_P1V8_STBY49,50P3V3_STBY_PG48,49
Title
Size Document Number R ev
Date: Sheet o f
Lightning PMC PEB -11PWRSW_P3V3_PWR_TPS53319Custom48 60Friday, March 31, 2017Lightning PMC PEB -1http://www.wiwynn.com8F, 90, Sec.1, Xintai 5th Rd., Xizhi Dist.,New Taipei City 22102, Taiwan (R.O.C.)
Title
Size Document Number R ev
Date: Sheet o f
Lightning PMC PEB -11PWRSW_P3V3_PWR_TPS53319Custom48 60Friday, March 31, 2017Lightning PMC PEB -1http://www.wiwynn.com8F, 90, Sec.1, Xintai 5th Rd., Xizhi Dist.,New Taipei City 22102, Taiwan (R.O.C.)
Title
Size Document Number R ev
Date: Sheet o f
Lightning PMC PEB -11PWRSW_P3V3_PWR_TPS53319Custom48 60Friday, March 31, 2017Lightning PMC PEB -1http://www.wiwynn.com8F, 90, Sec.1, Xintai 5th Rd., Xizhi Dist.,New Taipei City 22102, Taiwan (R.O.C.)
PR360R2J-2-GP12
PL3COIL-1D5UH-32-GP12
C267SC100P50V2JN-3GP
NOPOP
12
R6934K7R2F-GP12
PG8GAP-CLOSE-PWR-3-GP12
PR31 121KR2F-L-GP12
 Q43DSS4240T-7-GPCBE
PR2710R3F-GP12
PC32SC10U25V5KX-GP12
PC31SC1KP50V2KX-1GP12
PC223SC1U16V3KX-5GP
NOPOP
12
 Q422N7002K-1-GPGDS
PG9GAP-CLOSE-PWR-3-GP12
PC33SC10U25V5KX-GP12
PR262KR2F-3-GP12
R62856R6J-GP12
S
S
S
G D
D
D
D
Q3203P2003EVG-GP12345678
PR2510KR2F-2-GP12
Q402N7002K-1-GPGDS
Notice:ZZ.53319.07301PU2TPS53319DQPR-GPVFB1PGOOD3EN2VBST4ROVP5LL#66LL#77LL#88LL#99LL#1010LL#1111VIN12VIN13VIN14VIN15VIN16VIN17VREG18VDD19MODE20TRIP21RF22GND23
PR32 866KR2F-GPNOPOP12
 R69856R6J-GP12
PC22SC10U25V5KX-GP12
PC224SC1U16V3KX-5GP12
PL2BLM21PG220SN1DGP12
 PR3344K2R2F-1-GP12
PR35 619KR2F-GPNOPOP12
 PG4GAP-CLOSE-PWR-3-GP12
PR283D01R5F-GP
NOPOP
12
PC222SC1U16V3KX-5GP
NOPOP
12
PR242K7R2J-GP12
PC21SC10U25V5KX-GP12
 PG3COPPER-CLOSE-GP-U12
PC23SC10U25V5KX-GP12
PC26SC4D7U25V5KX-1-GP12
PC24SC10U25V5KX-GP12
PC40SC10U6D3V5KX-4GP12
 PG5GAP-CLOSE-PWR-3-GP12
PR192D2R3J-2-GP12
PC27SCD1U50V3KX-GP12
PC39SC10U6D3V5KX-4GP12
PC28SC2K2P50V3KX-GP
NOPOP
12
PR200R3J-0-U-GP12
PC29 SC1U10V2KX-4-GP12
PR181K4R2F-1-GP12
PC25SC10U25V5KX-GP12
 PG6GAP-CLOSE-PWR-3-GP12
R61847KR2F-GP12
PR30 100KR2F-L1-GPNOPOP12
 PR3710KR2F-2-GP12
PG7GAP-CLOSE-PWR-3-GP12
R7154K7R2F-GP12
 PC30SCD1U25V2KX-2-GP12
PTC38ST150U6D3VDM-28-GP12
 R62910KR2F-2-GP12
PR29 475KR2F-GP12



5
5
4
4
3
3
2
2
1
1
D D
C C
B B
A A
Power rail :P1V8_PWRController :TPS74801TDC :0.055AMax :0.055AOCP:2A
Vout=1.817V
VR_P1V8_STBY_BIASVR_P1V8_STBY_SS_CVR_P1V8_STBY_EN_RVR_P1V8_STBY_INVR_P1V8_STBY_FBVR_P1V8_STBY_INVR_P1V8_STBY_BIASP3V3_STBYP5V_STBYP1V8_PWRP3V3_STBYP1V8_STBYP1V8_PWRP1V8_PWRDUT_VDDOPWRGD_P1V8_STBY 48,49,50P3V3_STBY_PG48PWRGD_P1V8_STBY 48,49,50
Title
Size Document Number R e v
Date: Sheet o f
Lightning PMC PEB -11PWRLDO_P1V8_PWR_TPS74801A349 60Friday, March 31, 2017Lightning PMC PEB -1http://www.wiwynn.com8F, 90, Sec.1, Xintai 5th Rd., Xizhi Dist.,New Taipei City 22102, Taiwan (R.O.C.)
Title
Size Document Number R e v
Date: Sheet o f
Lightning PMC PEB -11PWRLDO_P1V8_PWR_TPS74801A349 60Friday, March 31, 2017Lightning PMC PEB -1http://www.wiwynn.com8F, 90, Sec.1, Xintai 5th Rd., Xizhi Dist.,New Taipei City 22102, Taiwan (R.O.C.)
Title
Size Document Number R e v
Date: Sheet o f
Lightning PMC PEB -11PWRLDO_P1V8_PWR_TPS74801A349 60Friday, March 31, 2017Lightning PMC PEB -1http://www.wiwynn.com8F, 90, Sec.1, Xintai 5th Rd., Xizhi Dist.,New Taipei City 22102, Taiwan (R.O.C.)
PC69SC4D7U16V5KX-1-GP12
PC86SCD01U25V2KX-3GP12
PC91SC10U10V5KX-6-GP-U12
 PC90SC22U6D3V5MX-5-GP12
PC93SC22U6D3V5MX-5-GP12
PG70GAP-CLOSE-PWR-3-GP12
PC92SC820P50V2KX-1GP12
 PR90342K87R2F-1-GP12
PG33GAP-CLOSE-PWR-3-GP12
PR90333K65R2F-1-GP12
PC89SC1KP50V2KX-1GP12
 PG10GAP-CLOSE-PWR-3-GP12
PC87SCD01U25V2KX-3GP
NOPOP
12
PR7810KR2F-2-GP12
PR770R3J-0-U-GP12
 PC88SC22U6D3V5MX-5-GP12
PU6TPS74801DRCR-1-GP-UIN#11IN#22PG3BIAS4EN5GND6SS7FB8OUT#99OUT#1010GND11
PR750R2J-2-GP12
PR740R3J-0-U-GP12



5
5
4
4
3
3
2
2
1
1
D D
C C
B B
A A
Vout=1.544V
Power rail :P1V53_PWRTDC :0.662AMax :0.662AOCP:2A
VR_P1V538_STBY_SS_CVR_P1V538_STBY_BIASVR_P1V538_STBY_INVR_P1V538_STBY_EN_RVR_P1V538_STBY_FBVR_P1V538_STBY_BIASVR_P1V538_STBY_INP5V_STBYP3V3_STBYP3V3_STBYP1V53_PWRP1V53_STBYP1V53_PWRPWRGD_P1V538_STBY 50,51PWRGD_P1V538_STBY 50,51PWRGD_P1V8_STBY48,49
Title
Size Document Number Rev
Date: Sheet o f
Lightning PMC PEB -11PWRLDO_P1V53_PWR_TPS74801Custom50 60Friday, March 31, 2017Lightning PMC PEB -1http://www.wiwynn.com8F, 90, Sec.1, Xintai 5th Rd., Xizhi Dist.,New Taipei City 22102, Taiwan (R.O.C.)
Title
Size Document Number Rev
Date: Sheet o f
Lightning PMC PEB -11PWRLDO_P1V53_PWR_TPS74801Custom50 60Friday, March 31, 2017Lightning PMC PEB -1http://www.wiwynn.com8F, 90, Sec.1, Xintai 5th Rd., Xizhi Dist.,New Taipei City 22102, Taiwan (R.O.C.)
Title
Size Document Number Rev
Date: Sheet o f
Lightning PMC PEB -11PWRLDO_P1V53_PWR_TPS74801Custom50 60Friday, March 31, 2017Lightning PMC PEB -1http://www.wiwynn.com8F, 90, Sec.1, Xintai 5th Rd., Xizhi Dist.,New Taipei City 22102, Taiwan (R.O.C.)
PR674K75R2F-1-GP12
PU4TPS74801DRCR-1-GP-UIN#11IN#22PG3BIAS4EN5GND6SS7FB8OUT#99OUT#1010GND11
PC74SCD01U25V2KX-3GP12
PC17SC820P50V2KX-1GP12
 PC18SCD01U25V2KX-3GP
NOPOP
12
PR230R3J-0-U-GP12
PG11GAP-CLOSE-PWR-3-GP12
PC95SC22U6D3V5MX-5-GP12
PC19SC22U6D3V5MX-5-GP12
PC70SC4D7U16V5KX-1-GP12
PG68GAP-CLOSE-PWR-3-GP12
PR624K42R2F-GP12
PR4310KR2F-2-GP12
PC20SC10U10V5KX-6-GP-U12
PR220R3J-0-U-GP12
 PC75SC22U6D3V5MX-5-GP12
PC76SC1KP50V2KX-1GP12
PR170R2J-2-GP12



5
5
4
4
3
3
2
2
1
1
D D
C C
B B
A A
Vout=1.2614V
Power rail :P1V26_PWRController :TPS74801TDC :0.766AMax :0.766AOCP:2A
PWRGD_P1V26_STBYVR_P1V26_STBY_EN_RVR_P1V26_STBY_SS_CVR_P1V26_STBY_BIASVR_P1V26_STBY_INVR_P1V26_STBY_FBVR_P1V26_STBY_BIASVR_P1V26_STBY_INP5V_STBYP3V3_STBYP3V3_STBYP1V26_PWRP1V26_STBYP1V26_PWRPWRGD_P1V26_STBY 14,52PWRGD_P1V538_STBY50
Title
Size Document Number R e v
Date: Sheet o f
Lightning PMC PEB -11PWRLDO_P1V26_PWR_TPS74801A351 60Friday, March 31, 2017Lightning PMC PEB -1http://www.wiwynn.com8F, 90, Sec.1, Xintai 5th Rd., Xizhi Dist.,New Taipei City 22102, Taiwan (R.O.C.)
Title
Size Document Number R e v
Date: Sheet o f
Lightning PMC PEB -11PWRLDO_P1V26_PWR_TPS74801A351 60Friday, March 31, 2017Lightning PMC PEB -1http://www.wiwynn.com8F, 90, Sec.1, Xintai 5th Rd., Xizhi Dist.,New Taipei City 22102, Taiwan (R.O.C.)
Title
Size Document Number R e v
Date: Sheet o f
Lightning PMC PEB -11PWRLDO_P1V26_PWR_TPS74801A351 60Friday, March 31, 2017Lightning PMC PEB -1http://www.wiwynn.com8F, 90, Sec.1, Xintai 5th Rd., Xizhi Dist.,New Taipei City 22102, Taiwan (R.O.C.)
PC80SC10U6D3V5KX-4GP12
 PC83SC1KP50V2KX-1GP
NOPOP
12
PU5TPS74801DRCR-1-GP-UIN#11IN#22PG3BIAS4EN5GND6SS7FB8OUT#99OUT#1010GND11
PC84SC820P50V2KX-1GP12
PC85SCD01U25V2KX-3GP12
PC82SC22U6D3V5MX-5-GP12
PG12GAP-CLOSE-PWR-3-GP12
PC78SCD01U25V2KX-3GP
NOPOP
12
PG69GAP-CLOSE-PWR-3-GP12
PR7310KR2F-2-GP12
PR704K75R2F-1-GP12
PC81SC22U6D3V5MX-5-GP12
PR912K74R2F-GP12
PR710R2J-2-GP12
 PC79SC22U6D3V5MX-5-GP12
PC77SC4D7U16V5KX-1-GP12
PR690R3J-0-U-GP12
PR720R3J-0-U-GP12



5
5
4
4
3
3
2
2
1
1
D D
C C
B B
A A
P0V9  SWITCHING TPS53355
Power rail :P0V9Controller :TPS53355Fswitch= 500KHzTDC : 16.7AMax : 16.7AOCP :20A
Low Vth=1V
Irate:61A  Isat:30A
P0V9_MODEP0V9_SW_RP0V9_ENP0V9_VBSTP0V9_VBST_RCP0V9_TRIPP0V9_RFP0V9_VDDP0V9_SNBP0V9_VFBP0V9_LXP0V9_VREG
P0V9_VFB_AVSAVS_ENB1_R
P0V9_VINP0V9_VFB_RP0V9_PGP0V9P0V9AGND_P0V9P12VAGND_P0V9AGND_P0V9AGND_P0V9
P12V
DUT_AVD_PCIEP0V9P0V9DUT_AVD_TX
AGND_P0V9DUT_VDDODUT_AVD_PCIEDUT_AVD_TXP3V3_STBYP0V9_PG53PWRGD_P1V26_STBY14,51AVS_ENB 36,53
Title
Size Document Number Rev
Date: Sheet o f
Lightning PMC PEB -11PWRSW_P0V9_TPS53355Custom52 60Friday, March 31, 2017Lightning PMC PEB -1http://www.wiwynn.com8F, 90, Sec.1, Xintai 5th Rd., Xizhi Dist.,New Taipei City 22102, Taiwan (R.O.C.)
Title
Size Document Number Rev
Date: Sheet o f
Lightning PMC PEB -11PWRSW_P0V9_TPS53355Custom52 60Friday, March 31, 2017Lightning PMC PEB -1http://www.wiwynn.com8F, 90, Sec.1, Xintai 5th Rd., Xizhi Dist.,New Taipei City 22102, Taiwan (R.O.C.)
Title
Size Document Number Rev
Date: Sheet o f
Lightning PMC PEB -11PWRSW_P0V9_TPS53355Custom52 60Friday, March 31, 2017Lightning PMC PEB -1http://www.wiwynn.com8F, 90, Sec.1, Xintai 5th Rd., Xizhi Dist.,New Taipei City 22102, Taiwan (R.O.C.)
PC208SCD1U16V2KX-3GP12
R760R2J-2-GP12
PG18GAP-CLOSE-PWR-3-GP12
PC204SC1U10V2KX-1GP
NOPOP
12
 PR1742K21R2F-GP12
 PG31GAP-CLOSE-PWR-3-GP12
PC197SC10U25V5KX-GP12
PG20GAP-CLOSE-PWR-3-GP12
PL10BLM41PG600-GP12
 PR18080K6R2F-GP12
PC205SC22U6D3V5MX-5-GP12
Notice:ZZ.53355.007301PU1TPS53355ADQPR-GPVFB1PGOOD3EN2VBST4NC#55LL#66LL#77LL#88LL#99LL#1010LL#1111VIN12VIN13VIN14VIN15VIN16VIN17VREG18VDD19MODE20TRIP21RF22GND23
C268SC100P50V2JN-3GP
NOPOP
12
PG19GAP-CLOSE-PWR-3-GP12
PC211SC22U25V6KX-GP-U12
PR1663D01R5F-GP
NOPOP
12
 PG32GAP-CLOSE-PWR-3-GP12
PC192SC10U25V5KX-GP12
PR17910KR2F-2-GP12
PR1590R3J-0-U-GP12
PR1684K53R2F-1-GP12
PR170475KR2F-GP12
PC206SC10U25V5KX-GP12
PG21GAP-CLOSE-PWR-3-GP12
PR17210D7R2F-GP12
PTC8SE470UF2VDM-GP12
PG34GAP-CLOSE-PWR-3-GP12
PG22GAP-CLOSE-PWR-3-GP12
R130R2J-2-GPNOPOP
12
R6820KR2F-L-GP12
PC210SC22U25V6KX-GP-U12
PR6284K7R2F-GP12
 PL11IND-300NH-8-GP12
PG23GAP-CLOSE-PWR-3-GP12
PC203SC1KP50V2KX-1GP12
PTC10SE470UF2VDM-GP12
PR382KR2J-GP12
PC212SC4D7U25V5KX-1-GP12
 PG35GAP-CLOSE-PWR-3-GP12
PC191SCD1U50V3KX-GP12
PC195SC10U25V5KX-GP12
PG25GAP-CLOSE-PWR-3-GP12
PQ19AO3400-GP-UGDS
PR169187KR2F-GP
NOPOP
12
PC201SC22U25V6KX-GP-U12
 PG24GAP-CLOSE-PWR-3-GP12PSP3COPPER-CLOSE-GP-U12
PC214SC22U25V6KX-GP-U12
PR1670R2J-2-GP12
 PG13GAP-CLOSE-PWR-3-GP12
PC198SC10U25V5KX-GP12
PG26GAP-CLOSE-PWR-3-GP12
PC94SC4D7U16V5KX-1-GP12
PC193SC1U16V3KX-5GP12
 PC202SC22U6D3V5MX-5-GP12
PC207SC470P50V2KX-3GP
NOPOP
12
PG14GAP-CLOSE-PWR-3-GP12
 R790R2J-2-GP12
PR17851KR2F-L-GP
NOPOP
12
PC213SC22U25V6KX-GP-U12
 PG27GAP-CLOSE-PWR-3-GP12
PC196SC22U25V6KX-GP-U12
PR175100KR2F-L1-GP
NOPOP
12
 PG15GAP-CLOSE-PWR-3-GP12
PR173100KR2F-L1-GP
NOPOP
12
PC199SC22U25V6KX-GP-U12
 PG28GAP-CLOSE-PWR-3-GP12
PG29GAP-CLOSE-PWR-3-GP12
PC209SC22U6D3V5MX-5-GP12
PG16GAP-CLOSE-PWR-3-GP12
PR1770R3J-0-U-GP12
PR176100KR2F-L1-GP
NOPOP
12
 PC200SCD1U50V3KX-GP12
PG17GAP-CLOSE-PWR-3-GP12
 PG30GAP-CLOSE-PWR-3-GP12
PC194SC22U6D3V5MX-5-GP12



5
5
4
4
3
3
2
2
1
1
D D
C C
B B
A A
Power rail :P0V9_EController :TPS53355Fswitch= 300KHzTDC : 26.32AMax : 26.32AOCP :30A
P0V9_E  SWITCHING TPS53355
Low Vth=1V
Irate:61A  Isat:40A
P0V9_E_VREGP0V9_E_MODEP0V9_E_SW_RP0V9_E_ENP0V9_E_VBSTP0V9_E_TRIPP0V9_E_VBST_RCP0V9_E_RFP0V9_E_VDDP0V9_E_SNBP0V9_E_VFBP0V9_E_LXP0V9_E_VFB_AVSAVS_ENB2_R
P0V9_E_VINP0V9_E_VINP0V9_E_VFB_RP0V9_E_PGP0V9_EP0V9_EAGND_P0V9_EAGND_P0V9_EAGND_P0V9_E
P12VAGND_P0V9_E
P12V
DUT_VDDP0V9_E
AGND_P0V9_EDUT_VDDODUT_VDDP3V3_STBYP0V9_PG52P0V9_E_PG13 AVS_ENB 36,52
Title
Size Document Number Rev
Date: Sheet o f
Lightning PMC PEB -11PWRSW_P0V9_E_TPS53355Custom53 60Friday, March 31, 2017Lightning PMC PEB -1http://www.wiwynn.com8F, 90, Sec.1, Xintai 5th Rd., Xizhi Dist.,New Taipei City 22102, Taiwan (R.O.C.)
Title
Size Document Number Rev
Date: Sheet o f
Lightning PMC PEB -11PWRSW_P0V9_E_TPS53355Custom53 60Friday, March 31, 2017Lightning PMC PEB -1http://www.wiwynn.com8F, 90, Sec.1, Xintai 5th Rd., Xizhi Dist.,New Taipei City 22102, Taiwan (R.O.C.)
Title
Size Document Number Rev
Date: Sheet o f
Lightning PMC PEB -11PWRSW_P0V9_E_TPS53355Custom53 60Friday, March 31, 2017Lightning PMC PEB -1http://www.wiwynn.com8F, 90, Sec.1, Xintai 5th Rd., Xizhi Dist.,New Taipei City 22102, Taiwan (R.O.C.)
PTC5SE470UF2VDM-GP12
PC181SC22U6D3V5MX-5-GP12
PG42GAP-CLOSE-PWR-3-GP12
PR163100KR2F-L1-GP
NOPOP
12
PR210R3J-0-U-GP12
PG58GAP-CLOSE-PWR-3-GP12
PC172SCD1U50V3KX-GP12
PQ20AO3400-GP-UGDS
PG43GAP-CLOSE-PWR-3-GP12
PC186SCD1U16V2KX-3GP12
PR1543D01R5F-GP
NOPOP
12
PC170SC10U25V5KX-GP12
Notice:ZZ.53355.007301PU3TPS53355ADQPR-GPVFB1PGOOD3EN2VBST4NC#55LL#66LL#77LL#88LL#99LL#1010LL#1111VIN12VIN13VIN14VIN15VIN16VIN17VREG18VDD19MODE20TRIP21RF22GND23
PC219SC22U25V6KX-GP-U12
 PG60GAP-CLOSE-PWR-3-GP12
PC179SC22U6D3V5MX-5-GP12
PTC7SE470UF2VDM-GP
NOPOP12
PR18280K6R2F-GP12
PC185SCD1U50V3KX-GP12
PG66GAP-CLOSE-PWR-3-GP12
PC176SC22U6D3V5MX-5-GP12
PG61GAP-CLOSE-PWR-3-GP12
PC184SC4D7U25V5KX-1-GP12
 PG48GAP-CLOSE-PWR-3-GP12
PC169SC10U25V5KX-GP12
 PG44GAP-CLOSE-PWR-3-GP12
PR2121KR2F-L-GP12
 PTC4SE470UF2VDM-GP12
PR1552K21R2F-GP12
PG64GAP-CLOSE-PWR-3-GP12
R800R2J-2-GP12
PC220SC22U25V6KX-GP-U12
 R220KR2F-L-GP12
PG62GAP-CLOSE-PWR-3-GP12
PG50GAP-CLOSE-PWR-3-GP12
PC178SC22U6D3V5MX-5-GP12
PR1520R2J-2-GP12
 PG67GAP-CLOSE-PWR-3-GP12
PR151100KR2F-L1-GP
NOPOP
12
 PR16510KR2F-2-GP12
PG63GAP-CLOSE-PWR-3-GP12
PG45GAP-CLOSE-PWR-3-GP12
PC175SC10U25V5KX-GP12
PG49GAP-CLOSE-PWR-3-GP12
PC174SC10U25V5KX-GP12
PC221SC22U25V6KX-GP-U12
PC187SC1U10V2KX-1GP
NOPOP
12
 PC177SC22U6D3V5MX-5-GP12
PC173SC10U25V5KX-GP12
PG65GAP-CLOSE-PWR-3-GP12
PG51GAP-CLOSE-PWR-3-GP12
PR15751KR2F-L-GP
NOPOP
12
 PG53GAP-CLOSE-PWR-3-GP12
PG46GAP-CLOSE-PWR-3-GP12
PC188SC470P50V2KX-3GP
NOPOP
12
PG36GAP-CLOSE-PWR-3-GP12
PSP2COPPER-CLOSE-GP-U12
PR158100KR2F-L1-GP
NOPOP
12
 PG52GAP-CLOSE-PWR-3-GP12
PC183SC22U6D3V5MX-5-GP12
PC215SC22U25V6KX-GP-U12
 PG37GAP-CLOSE-PWR-3-GP12
PG47GAP-CLOSE-PWR-3-GP12
PC180SC22U6D3V5MX-5-GP12
PG54GAP-CLOSE-PWR-3-GP12
PC216SC22U25V6KX-GP-U12
 PC182SC22U6D3V5MX-5-GP12
PL8BLM41PG600-GP12
PC190SC1U16V3KX-5GP12
PG39GAP-CLOSE-PWR-3-GP12
PC96SC4D7U16V5KX-1-GP12
PG55GAP-CLOSE-PWR-3-GP12
R140R2J-2-GP
NOPOP
12
PG38GAP-CLOSE-PWR-3-GP12
PG57GAP-CLOSE-PWR-3-GP12
PL9IND-320NH-4-GP12
PC217SC22U25V6KX-GP-U12
PR160475KR2F-GP12
 PG40GAP-CLOSE-PWR-3-GP12
PR1614K42R2F-GP12
PG56GAP-CLOSE-PWR-3-GP12
PTC6SE470UF2VDM-GP
NOPOP12
PR1500R3J-0-U-GP12
 PG41GAP-CLOSE-PWR-3-GP12
PC189SC1KP50V2KX-1GP12
PR162187KR2F-GP12
PC218SC22U25V6KX-GP-U12
 PG59GAP-CLOSE-PWR-3-GP12
PR15610D7R2F-GP12
R6104K7R2F-GP12
 C270SC100P50V2JN-3GP
NOPOP
12



5
5
4
4
3
3
2
2
1
1
D D
C C
B B
A A
ANCHOR
Title
Size Document Number R e v
Date: Sheet o f
Lightning PMC PEB -11ME MATERIALA354 60Friday, March 31, 2017Lightning PMC PEB -1http://www.wiwynn.com8F, 90, Sec.1, Xintai 5th Rd., Xizhi Dist.,New Taipei City 22102, Taiwan (R.O.C.)
Title
Size Document Number R e v
Date: Sheet o f
Lightning PMC PEB -11ME MATERIALA354 60Friday, March 31, 2017Lightning PMC PEB -1http://www.wiwynn.com8F, 90, Sec.1, Xintai 5th Rd., Xizhi Dist.,New Taipei City 22102, Taiwan (R.O.C.)
Title
Size Document Number R e v
Date: Sheet o f
Lightning PMC PEB -11ME MATERIALA354 60Friday, March 31, 2017Lightning PMC PEB -1http://www.wiwynn.com8F, 90, Sec.1, Xintai 5th Rd., Xizhi Dist.,New Taipei City 22102, Taiwan (R.O.C.)
PAD3PAD-3P-GPHT219X276B8R32-3P-S123
CN9FOX-CON2-S23-GP12
PAD2PAD-3P-GPHT24X28B8R32-3P-S123
PAD4PAD-2P-21-GPHT12X22B8R32-2P-S12
CN7FOX-CON2-S23-GP12